FILE_TYPE = MACRO_DRAWING;
SET COLOR_WIRE YELLOW;
SET COLOR_PROP MONO;
SET COLOR_DOT WHITE;
SET COLOR_ARC YELLOW;
SET COLOR_BODY GREEN;
SET COLOR_NOTE MONO;
SET PROP_DISPLAY VALUE;
SET PAGE_NUMBER P131;
FORCEADD CAP_A..1
(975 4975);
FORCEPROP 1 LAST LOCATION C7B15
J 0
(1025 5075);
DISPLAY 0.617021 (1025 5075);
PAINT AQUA (1025 5075);
FORCEPROP 1 LAST PART_NUMBER E15431-004
J 0
(1025 4825);
DISPLAY 0.617021 (1025 4825);
PAINT BLUE (1025 4825);
FORCEPROP 1 LAST VALUE 22.0UF
J 0
(1025 5025);
DISPLAY 0.617021 (1025 5025);
PAINT SKYBLUE (1025 5025);
FORCEPROP 1 LAST TOLERANCE 20%
J 0
(1025 4925);
DISPLAY 0.617021 (1025 4925);
PAINT SKYBLUE (1025 4925);
FORCEPROP 1 LAST PACK_TYPE 0603V
J 0
(1025 4775);
DISPLAY 0.617021 (1025 4775);
PAINT SKYBLUE (1025 4775);
FORCEPROP 1 LAST VOLTAGE 4V
J 0
(1025 4975);
DISPLAY 0.617021 (1025 4975);
PAINT SKYBLUE (1025 4975);
FORCEPROP 1 LAST MATERIAL X6S
J 0
(1025 4875);
DISPLAY 0.617021 (1025 4875);
PAINT SKYBLUE (1025 4875);
FORCEPROP 2 LAST CDS_LOCATION C7B15
J 0
(1025 5075);
DISPLAY 0.617021 (1025 5075);
PAINT AQUA (1025 5075);
DISPLAY INVISIBLE (1025 5075);
FORCEPROP 2 LAST BOM_COST SB
J 0
(1025 4725);
PAINT MONO (1025 4725);
DISPLAY INVISIBLE (1025 4725);
FORCEPROP 2 LAST CDS_LIB dev_discrete
J 0
(975 4975);
PAINT ORANGE (975 4975);
DISPLAY INVISIBLE (975 4975);
FORCEPROP 2 LAST CDS_SEC 1
J 0
(1025 5175);
DISPLAY 1.361702 (1025 5175);
PAINT ORANGE (1025 5175);
DISPLAY INVISIBLE (1025 5175);
FORCEPROP 2 LAST $SEC 1
J 0
(1025 5175);
DISPLAY 0.914894 (1025 5175);
PAINT MONO (1025 5175);
DISPLAY INVISIBLE (1025 5175);
FORCEPROP 1 LAST PATH I1
J 0
(1025 5125);
DISPLAY 0.978723 (1025 5125);
PAINT WHITE (1025 5125);
DISPLAY INVISIBLE (1025 5125);
FORCEPROP 2 LAST ROOM SB_DECOUPLING
J 0
(975 4975);
PAINT WHITE (975 4975);
DISPLAY INVISIBLE (975 4975);
FORCEPROP 1 LASTPIN (975 5075) $PN 1
J 0
(985 5055);
DISPLAY 1.063830 (985 5055);
PAINT WHITE (985 5055);
DISPLAY INVISIBLE (985 5055);
FORCEPROP 1 LASTPIN (975 4875) $PN 2
J 0
(985 4855);
DISPLAY 1.063830 (985 4855);
PAINT WHITE (985 4855);
DISPLAY INVISIBLE (985 4855);
FORCEADD CAP_A..1
(500 4025);
FORCEPROP 1 LAST LOCATION C7B22
J 0
(550 4125);
DISPLAY 0.617021 (550 4125);
PAINT AQUA (550 4125);
FORCEPROP 1 LAST PART_NUMBER E15431-004
J 0
(550 3875);
DISPLAY 0.617021 (550 3875);
PAINT BLUE (550 3875);
FORCEPROP 1 LAST VALUE 22.0UF
J 0
(550 4075);
DISPLAY 0.617021 (550 4075);
PAINT SKYBLUE (550 4075);
FORCEPROP 1 LAST TOLERANCE 20%
J 0
(550 3975);
DISPLAY 0.617021 (550 3975);
PAINT SKYBLUE (550 3975);
FORCEPROP 1 LAST PACK_TYPE 0603V
J 0
(550 3825);
DISPLAY 0.617021 (550 3825);
PAINT SKYBLUE (550 3825);
FORCEPROP 1 LAST VOLTAGE 4V
J 0
(550 4025);
DISPLAY 0.617021 (550 4025);
PAINT SKYBLUE (550 4025);
FORCEPROP 1 LAST MATERIAL X6S
J 0
(550 3925);
DISPLAY 0.617021 (550 3925);
PAINT SKYBLUE (550 3925);
FORCEPROP 2 LAST CDS_LOCATION C7B22
J 0
(550 4125);
DISPLAY 0.617021 (550 4125);
PAINT AQUA (550 4125);
DISPLAY INVISIBLE (550 4125);
FORCEPROP 2 LAST BOM_COST SB
J 0
(550 3775);
PAINT MONO (550 3775);
DISPLAY INVISIBLE (550 3775);
FORCEPROP 2 LAST CDS_LIB dev_discrete
J 0
(500 4025);
PAINT ORANGE (500 4025);
DISPLAY INVISIBLE (500 4025);
FORCEPROP 2 LAST CDS_SEC 1
J 0
(550 4225);
DISPLAY 1.361702 (550 4225);
PAINT ORANGE (550 4225);
DISPLAY INVISIBLE (550 4225);
FORCEPROP 2 LAST $SEC 1
J 0
(550 4225);
DISPLAY 0.914894 (550 4225);
PAINT MONO (550 4225);
DISPLAY INVISIBLE (550 4225);
FORCEPROP 1 LAST PATH I10
J 0
(550 4175);
DISPLAY 0.978723 (550 4175);
PAINT WHITE (550 4175);
DISPLAY INVISIBLE (550 4175);
FORCEPROP 2 LAST ROOM SB_DECOUPLING
J 0
(500 4025);
PAINT WHITE (500 4025);
DISPLAY INVISIBLE (500 4025);
FORCEPROP 1 LASTPIN (500 4125) $PN 1
J 0
(510 4105);
DISPLAY 1.063830 (510 4105);
PAINT WHITE (510 4105);
DISPLAY INVISIBLE (510 4105);
FORCEPROP 1 LASTPIN (500 3925) $PN 2
J 0
(510 3905);
DISPLAY 1.063830 (510 3905);
PAINT WHITE (510 3905);
DISPLAY INVISIBLE (510 3905);
FORCEADD CAP_A..1
(50 4025);
FORCEPROP 1 LAST LOCATION C7B24
J 0
(100 4125);
DISPLAY 0.617021 (100 4125);
PAINT AQUA (100 4125);
FORCEPROP 1 LAST PART_NUMBER E15431-004
J 0
(100 3875);
DISPLAY 0.617021 (100 3875);
PAINT BLUE (100 3875);
FORCEPROP 1 LAST VALUE 22.0UF
J 0
(100 4075);
DISPLAY 0.617021 (100 4075);
PAINT SKYBLUE (100 4075);
FORCEPROP 1 LAST TOLERANCE 20%
J 0
(100 3975);
DISPLAY 0.617021 (100 3975);
PAINT SKYBLUE (100 3975);
FORCEPROP 1 LAST PACK_TYPE 0603V
J 0
(100 3825);
DISPLAY 0.617021 (100 3825);
PAINT SKYBLUE (100 3825);
FORCEPROP 1 LAST VOLTAGE 4V
J 0
(100 4025);
DISPLAY 0.617021 (100 4025);
PAINT SKYBLUE (100 4025);
FORCEPROP 1 LAST MATERIAL X6S
J 0
(100 3925);
DISPLAY 0.617021 (100 3925);
PAINT SKYBLUE (100 3925);
FORCEPROP 2 LAST CDS_LOCATION C7B24
J 0
(100 4125);
DISPLAY 0.617021 (100 4125);
PAINT AQUA (100 4125);
DISPLAY INVISIBLE (100 4125);
FORCEPROP 2 LAST BOM_COST SB
J 0
(100 3775);
PAINT MONO (100 3775);
DISPLAY INVISIBLE (100 3775);
FORCEPROP 2 LAST CDS_LIB dev_discrete
J 0
(50 4025);
PAINT ORANGE (50 4025);
DISPLAY INVISIBLE (50 4025);
FORCEPROP 2 LAST CDS_SEC 1
J 0
(100 4225);
DISPLAY 1.361702 (100 4225);
PAINT ORANGE (100 4225);
DISPLAY INVISIBLE (100 4225);
FORCEPROP 2 LAST $SEC 1
J 0
(100 4225);
DISPLAY 0.914894 (100 4225);
PAINT MONO (100 4225);
DISPLAY INVISIBLE (100 4225);
FORCEPROP 1 LAST PATH I11
J 0
(100 4175);
DISPLAY 0.978723 (100 4175);
PAINT WHITE (100 4175);
DISPLAY INVISIBLE (100 4175);
FORCEPROP 2 LAST ROOM SB_DECOUPLING
J 0
(50 4025);
PAINT WHITE (50 4025);
DISPLAY INVISIBLE (50 4025);
FORCEPROP 1 LASTPIN (50 4125) $PN 1
J 0
(60 4105);
DISPLAY 1.063830 (60 4105);
PAINT WHITE (60 4105);
DISPLAY INVISIBLE (60 4105);
FORCEPROP 1 LASTPIN (50 3925) $PN 2
J 0
(60 3905);
DISPLAY 1.063830 (60 3905);
PAINT WHITE (60 3905);
DISPLAY INVISIBLE (60 3905);
FORCEADD CAP_A..1
(-425 4025);
FORCEPROP 1 LAST LOCATION C7B18
J 0
(-375 4125);
DISPLAY 0.617021 (-375 4125);
PAINT AQUA (-375 4125);
FORCEPROP 1 LAST PART_NUMBER E15431-004
J 0
(-375 3875);
DISPLAY 0.617021 (-375 3875);
PAINT BLUE (-375 3875);
FORCEPROP 1 LAST VALUE 22.0UF
J 0
(-375 4075);
DISPLAY 0.617021 (-375 4075);
PAINT SKYBLUE (-375 4075);
FORCEPROP 1 LAST TOLERANCE 20%
J 0
(-375 3975);
DISPLAY 0.617021 (-375 3975);
PAINT SKYBLUE (-375 3975);
FORCEPROP 1 LAST PACK_TYPE 0603V
J 0
(-375 3825);
DISPLAY 0.617021 (-375 3825);
PAINT SKYBLUE (-375 3825);
FORCEPROP 1 LAST VOLTAGE 4V
J 0
(-375 4025);
DISPLAY 0.617021 (-375 4025);
PAINT SKYBLUE (-375 4025);
FORCEPROP 1 LAST MATERIAL X6S
J 0
(-375 3925);
DISPLAY 0.617021 (-375 3925);
PAINT SKYBLUE (-375 3925);
FORCEPROP 2 LAST CDS_LOCATION C7B18
J 0
(-375 4125);
DISPLAY 0.617021 (-375 4125);
PAINT AQUA (-375 4125);
DISPLAY INVISIBLE (-375 4125);
FORCEPROP 2 LAST BOM_COST SB
J 0
(-375 3775);
PAINT MONO (-375 3775);
DISPLAY INVISIBLE (-375 3775);
FORCEPROP 2 LAST CDS_LIB dev_discrete
J 0
(-425 4025);
PAINT ORANGE (-425 4025);
DISPLAY INVISIBLE (-425 4025);
FORCEPROP 2 LAST CDS_SEC 1
J 0
(-375 4225);
DISPLAY 1.361702 (-375 4225);
PAINT ORANGE (-375 4225);
DISPLAY INVISIBLE (-375 4225);
FORCEPROP 2 LAST $SEC 1
J 0
(-375 4225);
DISPLAY 0.914894 (-375 4225);
PAINT MONO (-375 4225);
DISPLAY INVISIBLE (-375 4225);
FORCEPROP 1 LAST PATH I12
J 0
(-375 4175);
DISPLAY 0.978723 (-375 4175);
PAINT WHITE (-375 4175);
DISPLAY INVISIBLE (-375 4175);
FORCEPROP 2 LAST ROOM SB_DECOUPLING
J 0
(-425 4025);
PAINT WHITE (-425 4025);
DISPLAY INVISIBLE (-425 4025);
FORCEPROP 1 LASTPIN (-425 4125) $PN 1
J 0
(-415 4105);
DISPLAY 1.063830 (-415 4105);
PAINT WHITE (-415 4105);
DISPLAY INVISIBLE (-415 4105);
FORCEPROP 1 LASTPIN (-425 3925) $PN 2
J 0
(-415 3905);
DISPLAY 1.063830 (-415 3905);
PAINT WHITE (-415 3905);
DISPLAY INVISIBLE (-415 3905);
FORCEADD GND..1
(275 3650);
FORCEPROP 3 LASTPIN (275 3700) SIG_NAME GND\g
J 0
(285 3710);
DISPLAY 0.659574 (285 3710);
PAINT MONO (285 3710);
DISPLAY INVISIBLE (285 3710);
FORCEPROP 1 LAST VOLTAGE 0
J 0
(275 3650);
PAINT SKYBLUE (275 3650);
DISPLAY INVISIBLE (275 3650);
FORCEPROP 1 LAST SIZE 1B
J 0
(350 3600);
DISPLAY 1.404255 (350 3600);
PAINT GREEN (350 3600);
DISPLAY INVISIBLE (350 3600);
FORCEPROP 2 LAST CDS_LIB mstr_symbols
J 0
(275 3650);
PAINT ORANGE (275 3650);
DISPLAY INVISIBLE (275 3650);
FORCEPROP 2 LAST BOM_COST SB
J 0
(225 3725);
PAINT MONO (225 3725);
DISPLAY INVISIBLE (225 3725);
FORCEPROP 1 LAST BODY_TYPE PLUMBING
J 0
(230 3607);
DISPLAY 0.340426 (230 3607);
PAINT GREEN (230 3607);
DISPLAY INVISIBLE (230 3607);
FORCEPROP 1 LAST PATH I13
J 0
(350 3650);
DISPLAY 0.872340 (350 3650);
PAINT AQUA (350 3650);
DISPLAY INVISIBLE (350 3650);
FORCEPROP 2 LAST ROOM SB_DECOUPLING
J 0
(-200 3725);
PAINT WHITE (-200 3725);
DISPLAY INVISIBLE (-200 3725);
FORCEPROP 1 LAST HDL_POWER GND
J 0
(275 3800);
DISPLAY 1.404255 (275 3800);
PAINT GREEN (275 3800);
DISPLAY INVISIBLE (275 3800);
FORCEADD CAP_A..1
(500 3025);
FORCEPROP 1 LAST LOCATION C8B9
J 0
(550 3125);
DISPLAY 0.617021 (550 3125);
PAINT AQUA (550 3125);
FORCEPROP 1 LAST PART_NUMBER E15431-004
J 0
(550 2875);
DISPLAY 0.617021 (550 2875);
PAINT BLUE (550 2875);
FORCEPROP 1 LAST VALUE 22.0UF
J 0
(550 3075);
DISPLAY 0.617021 (550 3075);
PAINT SKYBLUE (550 3075);
FORCEPROP 1 LAST TOLERANCE 20%
J 0
(550 2975);
DISPLAY 0.617021 (550 2975);
PAINT SKYBLUE (550 2975);
FORCEPROP 1 LAST PACK_TYPE 0603V
J 0
(550 2825);
DISPLAY 0.617021 (550 2825);
PAINT SKYBLUE (550 2825);
FORCEPROP 1 LAST VOLTAGE 4V
J 0
(550 3025);
DISPLAY 0.617021 (550 3025);
PAINT SKYBLUE (550 3025);
FORCEPROP 1 LAST MATERIAL X6S
J 0
(550 2925);
DISPLAY 0.617021 (550 2925);
PAINT SKYBLUE (550 2925);
FORCEPROP 1 LASTPIN (500 3125) $PN 1
J 0
(510 3105);
DISPLAY 0.617021 (510 3105);
PAINT WHITE (510 3105);
FORCEPROP 1 LASTPIN (500 2925) $PN 2
J 0
(510 2905);
DISPLAY 0.617021 (510 2905);
PAINT WHITE (510 2905);
FORCEPROP 2 LAST CDS_LOCATION C8B9
J 0
(550 3125);
DISPLAY 0.617021 (550 3125);
PAINT AQUA (550 3125);
DISPLAY INVISIBLE (550 3125);
FORCEPROP 2 LAST BOM_COST SB
J 0
(550 3225);
DISPLAY 1.361702 (550 3225);
PAINT ORANGE (550 3225);
DISPLAY INVISIBLE (550 3225);
FORCEPROP 2 LAST CDS_LIB dev_discrete
J 0
(500 3025);
PAINT ORANGE (500 3025);
DISPLAY INVISIBLE (500 3025);
FORCEPROP 2 LAST CDS_SEC 1
J 0
(550 3225);
DISPLAY 1.361702 (550 3225);
PAINT ORANGE (550 3225);
DISPLAY INVISIBLE (550 3225);
FORCEPROP 2 LAST $SEC 1
J 0
(550 3225);
DISPLAY 0.914894 (550 3225);
PAINT MONO (550 3225);
DISPLAY INVISIBLE (550 3225);
FORCEPROP 1 LAST PATH I14
J 0
(550 3175);
DISPLAY 0.978723 (550 3175);
PAINT WHITE (550 3175);
DISPLAY INVISIBLE (550 3175);
FORCEPROP 2 LAST ROOM SB_DECOUPLING
J 0
(550 3175);
DISPLAY 1.361702 (550 3175);
PAINT ORANGE (550 3175);
DISPLAY INVISIBLE (550 3175);
FORCEADD CAP_A..1
(50 3025);
FORCEPROP 1 LAST LOCATION C8B11
J 0
(100 3125);
DISPLAY 0.617021 (100 3125);
PAINT AQUA (100 3125);
FORCEPROP 1 LAST PART_NUMBER E15431-004
J 0
(100 2875);
DISPLAY 0.617021 (100 2875);
PAINT BLUE (100 2875);
FORCEPROP 1 LAST VALUE 22.0UF
J 0
(100 3075);
DISPLAY 0.617021 (100 3075);
PAINT SKYBLUE (100 3075);
FORCEPROP 1 LAST TOLERANCE 20%
J 0
(100 2975);
DISPLAY 0.617021 (100 2975);
PAINT SKYBLUE (100 2975);
FORCEPROP 1 LAST PACK_TYPE 0603V
J 0
(100 2825);
DISPLAY 0.617021 (100 2825);
PAINT SKYBLUE (100 2825);
FORCEPROP 1 LAST VOLTAGE 4V
J 0
(100 3025);
DISPLAY 0.617021 (100 3025);
PAINT SKYBLUE (100 3025);
FORCEPROP 1 LAST MATERIAL X6S
J 0
(100 2925);
DISPLAY 0.617021 (100 2925);
PAINT SKYBLUE (100 2925);
FORCEPROP 1 LASTPIN (50 3125) $PN 1
J 0
(60 3105);
DISPLAY 0.617021 (60 3105);
PAINT WHITE (60 3105);
FORCEPROP 1 LASTPIN (50 2925) $PN 2
J 0
(60 2905);
DISPLAY 0.617021 (60 2905);
PAINT WHITE (60 2905);
FORCEPROP 2 LAST CDS_LOCATION C8B11
J 0
(100 3125);
DISPLAY 0.617021 (100 3125);
PAINT AQUA (100 3125);
DISPLAY INVISIBLE (100 3125);
FORCEPROP 2 LAST BOM_COST SB
J 0
(100 3225);
DISPLAY 1.361702 (100 3225);
PAINT ORANGE (100 3225);
DISPLAY INVISIBLE (100 3225);
FORCEPROP 2 LAST CDS_LIB dev_discrete
J 0
(50 3025);
PAINT ORANGE (50 3025);
DISPLAY INVISIBLE (50 3025);
FORCEPROP 2 LAST CDS_SEC 1
J 0
(100 3225);
DISPLAY 1.361702 (100 3225);
PAINT ORANGE (100 3225);
DISPLAY INVISIBLE (100 3225);
FORCEPROP 2 LAST $SEC 1
J 0
(100 3225);
DISPLAY 0.914894 (100 3225);
PAINT MONO (100 3225);
DISPLAY INVISIBLE (100 3225);
FORCEPROP 1 LAST PATH I15
J 0
(100 3175);
DISPLAY 0.978723 (100 3175);
PAINT WHITE (100 3175);
DISPLAY INVISIBLE (100 3175);
FORCEPROP 2 LAST ROOM SB_DECOUPLING
J 0
(100 3175);
DISPLAY 1.361702 (100 3175);
PAINT ORANGE (100 3175);
DISPLAY INVISIBLE (100 3175);
FORCEADD CAP_A..1
(-400 3025);
FORCEPROP 1 LAST LOCATION C8B14
J 0
(-350 3125);
DISPLAY 0.617021 (-350 3125);
PAINT AQUA (-350 3125);
FORCEPROP 1 LAST PART_NUMBER E15431-004
J 0
(-350 2875);
DISPLAY 0.617021 (-350 2875);
PAINT BLUE (-350 2875);
FORCEPROP 1 LAST VALUE 22.0UF
J 0
(-350 3075);
DISPLAY 0.617021 (-350 3075);
PAINT SKYBLUE (-350 3075);
FORCEPROP 1 LAST TOLERANCE 20%
J 0
(-350 2975);
DISPLAY 0.617021 (-350 2975);
PAINT SKYBLUE (-350 2975);
FORCEPROP 1 LAST PACK_TYPE 0603V
J 0
(-350 2825);
DISPLAY 0.617021 (-350 2825);
PAINT SKYBLUE (-350 2825);
FORCEPROP 1 LAST VOLTAGE 4V
J 0
(-350 3025);
DISPLAY 0.617021 (-350 3025);
PAINT SKYBLUE (-350 3025);
FORCEPROP 1 LAST MATERIAL X6S
J 0
(-350 2925);
DISPLAY 0.617021 (-350 2925);
PAINT SKYBLUE (-350 2925);
FORCEPROP 1 LASTPIN (-400 3125) $PN 1
J 0
(-390 3105);
DISPLAY 0.617021 (-390 3105);
PAINT WHITE (-390 3105);
FORCEPROP 1 LASTPIN (-400 2925) $PN 2
J 0
(-390 2905);
DISPLAY 0.617021 (-390 2905);
PAINT WHITE (-390 2905);
FORCEPROP 2 LAST CDS_LOCATION C8B14
J 0
(-350 3125);
DISPLAY 0.617021 (-350 3125);
PAINT AQUA (-350 3125);
DISPLAY INVISIBLE (-350 3125);
FORCEPROP 2 LAST BOM_COST SB
J 0
(-350 3225);
DISPLAY 1.361702 (-350 3225);
PAINT ORANGE (-350 3225);
DISPLAY INVISIBLE (-350 3225);
FORCEPROP 2 LAST CDS_LIB dev_discrete
J 0
(-400 3025);
PAINT ORANGE (-400 3025);
DISPLAY INVISIBLE (-400 3025);
FORCEPROP 2 LAST CDS_SEC 1
J 0
(-350 3225);
DISPLAY 1.361702 (-350 3225);
PAINT ORANGE (-350 3225);
DISPLAY INVISIBLE (-350 3225);
FORCEPROP 2 LAST $SEC 1
J 0
(-350 3225);
DISPLAY 0.914894 (-350 3225);
PAINT MONO (-350 3225);
DISPLAY INVISIBLE (-350 3225);
FORCEPROP 1 LAST PATH I16
J 0
(-350 3175);
DISPLAY 0.978723 (-350 3175);
PAINT WHITE (-350 3175);
DISPLAY INVISIBLE (-350 3175);
FORCEPROP 2 LAST ROOM SB_DECOUPLING
J 0
(-350 3175);
DISPLAY 1.361702 (-350 3175);
PAINT ORANGE (-350 3175);
DISPLAY INVISIBLE (-350 3175);
FORCEADD P1V05_PCH_STBY..1
(-625 4300);
FORCEPROP 3 LASTPIN (-625 4250) SIG_NAME P1V05_PCH_STBY\g
J 0
(-615 4260);
DISPLAY 0.659574 (-615 4260);
PAINT MONO (-615 4260);
DISPLAY INVISIBLE (-615 4260);
FORCEPROP 1 LAST VOLTAGE 1.05V
J 0
(-670 4257);
DISPLAY 0.340426 (-670 4257);
PAINT SKYBLUE (-670 4257);
DISPLAY INVISIBLE (-670 4257);
FORCEPROP 2 LAST BOM_COST SB
J 0
(-625 4450);
PAINT MONO (-625 4450);
DISPLAY INVISIBLE (-625 4450);
FORCEPROP 2 LAST CDS_LIB mstr_symbols
J 0
(-625 4300);
PAINT ORANGE (-625 4300);
DISPLAY INVISIBLE (-625 4300);
FORCEPROP 1 LAST BODY_TYPE PLUMBING
J 0
(-670 4257);
DISPLAY 0.340426 (-670 4257);
PAINT GREEN (-670 4257);
DISPLAY INVISIBLE (-670 4257);
FORCEPROP 1 LAST PATH I17
J 0
(-575 4325);
DISPLAY 0.872340 (-575 4325);
PAINT AQUA (-575 4325);
DISPLAY INVISIBLE (-575 4325);
FORCEPROP 2 LAST ROOM SB_DECOUPLING
J 0
(-625 4400);
DISPLAY 1.361702 (-625 4400);
PAINT WHITE (-625 4400);
DISPLAY INVISIBLE (-625 4400);
FORCEPROP 1 LAST HDL_POWER P1V05_PCH_STBY
J 0
(-625 4350);
DISPLAY 0.872340 (-625 4350);
PAINT GREEN (-625 4350);
DISPLAY INVISIBLE (-625 4350);
FORCEADD CAP_A..1
(-875 4025);
FORCEPROP 1 LAST LOCATION C7B17
J 0
(-825 4125);
DISPLAY 0.617021 (-825 4125);
PAINT AQUA (-825 4125);
FORCEPROP 1 LAST PART_NUMBER E15431-004
J 0
(-825 3875);
DISPLAY 0.617021 (-825 3875);
PAINT BLUE (-825 3875);
FORCEPROP 1 LAST VALUE 22.0UF
J 0
(-825 4075);
DISPLAY 0.617021 (-825 4075);
PAINT SKYBLUE (-825 4075);
FORCEPROP 1 LAST TOLERANCE 20%
J 0
(-825 3975);
DISPLAY 0.617021 (-825 3975);
PAINT SKYBLUE (-825 3975);
FORCEPROP 1 LAST PACK_TYPE 0603V
J 0
(-825 3825);
DISPLAY 0.617021 (-825 3825);
PAINT SKYBLUE (-825 3825);
FORCEPROP 1 LAST VOLTAGE 4V
J 0
(-825 4025);
DISPLAY 0.617021 (-825 4025);
PAINT SKYBLUE (-825 4025);
FORCEPROP 1 LAST MATERIAL X6S
J 0
(-825 3925);
DISPLAY 0.617021 (-825 3925);
PAINT SKYBLUE (-825 3925);
FORCEPROP 2 LAST CDS_LOCATION C7B17
J 0
(-825 4125);
DISPLAY 0.617021 (-825 4125);
PAINT AQUA (-825 4125);
DISPLAY INVISIBLE (-825 4125);
FORCEPROP 2 LAST BOM_COST SB
J 0
(-825 3775);
PAINT MONO (-825 3775);
DISPLAY INVISIBLE (-825 3775);
FORCEPROP 2 LAST CDS_LIB dev_discrete
J 0
(-875 4025);
PAINT ORANGE (-875 4025);
DISPLAY INVISIBLE (-875 4025);
FORCEPROP 2 LAST CDS_SEC 1
J 0
(-825 4225);
DISPLAY 1.361702 (-825 4225);
PAINT ORANGE (-825 4225);
DISPLAY INVISIBLE (-825 4225);
FORCEPROP 2 LAST $SEC 1
J 0
(-825 4225);
DISPLAY 0.914894 (-825 4225);
PAINT MONO (-825 4225);
DISPLAY INVISIBLE (-825 4225);
FORCEPROP 1 LAST PATH I18
J 0
(-825 4175);
DISPLAY 0.978723 (-825 4175);
PAINT WHITE (-825 4175);
DISPLAY INVISIBLE (-825 4175);
FORCEPROP 2 LAST ROOM SB_DECOUPLING
J 0
(-875 4025);
PAINT WHITE (-875 4025);
DISPLAY INVISIBLE (-875 4025);
FORCEPROP 1 LASTPIN (-875 4125) $PN 1
J 0
(-865 4105);
DISPLAY 1.063830 (-865 4105);
PAINT WHITE (-865 4105);
DISPLAY INVISIBLE (-865 4105);
FORCEPROP 1 LASTPIN (-875 3925) $PN 2
J 0
(-865 3905);
DISPLAY 1.063830 (-865 3905);
PAINT WHITE (-865 3905);
DISPLAY INVISIBLE (-865 3905);
FORCEADD P1V05_PCH_STBY..1
(-625 3325);
FORCEPROP 3 LASTPIN (-625 3275) SIG_NAME P1V05_PCH_STBY\g
J 0
(-615 3285);
DISPLAY 0.659574 (-615 3285);
PAINT MONO (-615 3285);
DISPLAY INVISIBLE (-615 3285);
FORCEPROP 1 LAST VOLTAGE 1.05V
J 0
(-670 3282);
DISPLAY 0.340426 (-670 3282);
PAINT SKYBLUE (-670 3282);
DISPLAY INVISIBLE (-670 3282);
FORCEPROP 2 LAST BOM_COST SB
J 0
(-625 3425);
DISPLAY 1.361702 (-625 3425);
PAINT ORANGE (-625 3425);
DISPLAY INVISIBLE (-625 3425);
FORCEPROP 2 LAST CDS_LIB mstr_symbols
J 0
(-625 3325);
PAINT ORANGE (-625 3325);
DISPLAY INVISIBLE (-625 3325);
FORCEPROP 1 LAST BODY_TYPE PLUMBING
J 0
(-670 3282);
DISPLAY 0.340426 (-670 3282);
PAINT GREEN (-670 3282);
DISPLAY INVISIBLE (-670 3282);
FORCEPROP 1 LAST PATH I19
J 0
(-575 3350);
DISPLAY 0.872340 (-575 3350);
PAINT AQUA (-575 3350);
DISPLAY INVISIBLE (-575 3350);
FORCEPROP 2 LAST ROOM SB_DECOUPLING
J 0
(-625 3425);
DISPLAY 1.361702 (-625 3425);
PAINT ORANGE (-625 3425);
DISPLAY INVISIBLE (-625 3425);
FORCEPROP 1 LAST HDL_POWER P1V05_PCH_STBY
J 0
(-625 3375);
DISPLAY 0.872340 (-625 3375);
PAINT GREEN (-625 3375);
DISPLAY INVISIBLE (-625 3375);
FORCEADD CAP_A..1
(500 4975);
FORCEPROP 1 LAST LOCATION C7B19
J 0
(550 5075);
DISPLAY 0.617021 (550 5075);
PAINT AQUA (550 5075);
FORCEPROP 1 LAST PART_NUMBER E15431-004
J 0
(550 4825);
DISPLAY 0.617021 (550 4825);
PAINT BLUE (550 4825);
FORCEPROP 1 LAST VALUE 22.0UF
J 0
(550 5025);
DISPLAY 0.617021 (550 5025);
PAINT SKYBLUE (550 5025);
FORCEPROP 1 LAST TOLERANCE 20%
J 0
(550 4925);
DISPLAY 0.617021 (550 4925);
PAINT SKYBLUE (550 4925);
FORCEPROP 1 LAST PACK_TYPE 0603V
J 0
(550 4775);
DISPLAY 0.617021 (550 4775);
PAINT SKYBLUE (550 4775);
FORCEPROP 1 LAST VOLTAGE 4V
J 0
(550 4975);
DISPLAY 0.617021 (550 4975);
PAINT SKYBLUE (550 4975);
FORCEPROP 1 LAST MATERIAL X6S
J 0
(550 4875);
DISPLAY 0.617021 (550 4875);
PAINT SKYBLUE (550 4875);
FORCEPROP 2 LAST CDS_LOCATION C7B19
J 0
(550 5075);
DISPLAY 0.617021 (550 5075);
PAINT AQUA (550 5075);
DISPLAY INVISIBLE (550 5075);
FORCEPROP 2 LAST BOM_COST SB
J 0
(550 4725);
PAINT MONO (550 4725);
DISPLAY INVISIBLE (550 4725);
FORCEPROP 2 LAST CDS_LIB dev_discrete
J 0
(500 4975);
PAINT ORANGE (500 4975);
DISPLAY INVISIBLE (500 4975);
FORCEPROP 2 LAST CDS_SEC 1
J 0
(550 5175);
DISPLAY 1.361702 (550 5175);
PAINT ORANGE (550 5175);
DISPLAY INVISIBLE (550 5175);
FORCEPROP 2 LAST $SEC 1
J 0
(550 5175);
DISPLAY 0.914894 (550 5175);
PAINT MONO (550 5175);
DISPLAY INVISIBLE (550 5175);
FORCEPROP 1 LAST PATH I2
J 0
(550 5125);
DISPLAY 0.978723 (550 5125);
PAINT WHITE (550 5125);
DISPLAY INVISIBLE (550 5125);
FORCEPROP 2 LAST ROOM SB_DECOUPLING
J 0
(500 4975);
PAINT WHITE (500 4975);
DISPLAY INVISIBLE (500 4975);
FORCEPROP 1 LASTPIN (500 5075) $PN 1
J 0
(510 5055);
DISPLAY 1.063830 (510 5055);
PAINT WHITE (510 5055);
DISPLAY INVISIBLE (510 5055);
FORCEPROP 1 LASTPIN (500 4875) $PN 2
J 0
(510 4855);
DISPLAY 1.063830 (510 4855);
PAINT WHITE (510 4855);
DISPLAY INVISIBLE (510 4855);
FORCEADD CAP_A..1
(-850 3025);
FORCEPROP 1 LAST LOCATION C8B13
J 0
(-800 3125);
DISPLAY 0.617021 (-800 3125);
PAINT AQUA (-800 3125);
FORCEPROP 1 LAST PART_NUMBER E15431-004
J 0
(-800 2875);
DISPLAY 0.617021 (-800 2875);
PAINT BLUE (-800 2875);
FORCEPROP 1 LAST VALUE 22.0UF
J 0
(-800 3075);
DISPLAY 0.617021 (-800 3075);
PAINT SKYBLUE (-800 3075);
FORCEPROP 1 LAST TOLERANCE 20%
J 0
(-800 2975);
DISPLAY 0.617021 (-800 2975);
PAINT SKYBLUE (-800 2975);
FORCEPROP 1 LAST PACK_TYPE 0603V
J 0
(-800 2825);
DISPLAY 0.617021 (-800 2825);
PAINT SKYBLUE (-800 2825);
FORCEPROP 1 LAST VOLTAGE 4V
J 0
(-800 3025);
DISPLAY 0.617021 (-800 3025);
PAINT SKYBLUE (-800 3025);
FORCEPROP 1 LAST MATERIAL X6S
J 0
(-800 2925);
DISPLAY 0.617021 (-800 2925);
PAINT SKYBLUE (-800 2925);
FORCEPROP 1 LASTPIN (-850 3125) $PN 1
J 0
(-840 3105);
DISPLAY 0.617021 (-840 3105);
PAINT WHITE (-840 3105);
FORCEPROP 1 LASTPIN (-850 2925) $PN 2
J 0
(-840 2905);
DISPLAY 0.617021 (-840 2905);
PAINT WHITE (-840 2905);
FORCEPROP 2 LAST CDS_LOCATION C8B13
J 0
(-800 3125);
DISPLAY 0.617021 (-800 3125);
PAINT AQUA (-800 3125);
DISPLAY INVISIBLE (-800 3125);
FORCEPROP 2 LAST BOM_COST SB
J 0
(-800 3225);
DISPLAY 1.361702 (-800 3225);
PAINT ORANGE (-800 3225);
DISPLAY INVISIBLE (-800 3225);
FORCEPROP 2 LAST CDS_LIB dev_discrete
J 0
(-850 3025);
PAINT ORANGE (-850 3025);
DISPLAY INVISIBLE (-850 3025);
FORCEPROP 2 LAST CDS_SEC 1
J 0
(-800 3225);
DISPLAY 1.361702 (-800 3225);
PAINT ORANGE (-800 3225);
DISPLAY INVISIBLE (-800 3225);
FORCEPROP 2 LAST $SEC 1
J 0
(-800 3225);
DISPLAY 0.914894 (-800 3225);
PAINT MONO (-800 3225);
DISPLAY INVISIBLE (-800 3225);
FORCEPROP 1 LAST PATH I20
J 0
(-800 3175);
DISPLAY 0.978723 (-800 3175);
PAINT WHITE (-800 3175);
DISPLAY INVISIBLE (-800 3175);
FORCEPROP 2 LAST ROOM SB_DECOUPLING
J 0
(-800 3175);
DISPLAY 1.361702 (-800 3175);
PAINT ORANGE (-800 3175);
DISPLAY INVISIBLE (-800 3175);
FORCEADD GND..1
(275 2675);
FORCEPROP 3 LASTPIN (275 2725) SIG_NAME GND\g
J 0
(285 2735);
DISPLAY 0.659574 (285 2735);
PAINT MONO (285 2735);
DISPLAY INVISIBLE (285 2735);
FORCEPROP 1 LAST VOLTAGE 0.0V
J 0
(230 2632);
DISPLAY 0.340426 (230 2632);
PAINT SKYBLUE (230 2632);
DISPLAY INVISIBLE (230 2632);
FORCEPROP 1 LAST SIZE 1B
J 0
(350 2625);
DISPLAY 1.170213 (350 2625);
PAINT AQUA (350 2625);
DISPLAY INVISIBLE (350 2625);
FORCEPROP 2 LAST CDS_LIB mstr_symbols
J 0
(275 2675);
PAINT MONO (275 2675);
DISPLAY INVISIBLE (275 2675);
FORCEPROP 2 LAST BOM_COST SB
J 0
(300 2750);
DISPLAY 1.361702 (300 2750);
PAINT ORANGE (300 2750);
DISPLAY INVISIBLE (300 2750);
FORCEPROP 1 LAST BODY_TYPE PLUMBING
J 0
(230 2632);
DISPLAY 0.340426 (230 2632);
PAINT GREEN (230 2632);
DISPLAY INVISIBLE (230 2632);
FORCEPROP 1 LAST PATH I21
J 0
(350 2675);
DISPLAY 0.872340 (350 2675);
PAINT AQUA (350 2675);
DISPLAY INVISIBLE (350 2675);
FORCEPROP 2 LAST ROOM SB_DECOUPLING
J 0
(300 2750);
DISPLAY 1.361702 (300 2750);
PAINT ORANGE (300 2750);
DISPLAY INVISIBLE (300 2750);
FORCEPROP 1 LAST HDL_POWER GND
J 0
(275 2825);
DISPLAY 1.170213 (275 2825);
PAINT GREEN (275 2825);
DISPLAY INVISIBLE (275 2825);
FORCEADD CAP..1
(50 2025);
FORCEPROP 1 LAST LOCATION C8B16
J 0
(100 2125);
DISPLAY 0.617021 (100 2125);
PAINT AQUA (100 2125);
FORCEPROP 1 LAST PART_NUMBER C95333-006
J 0
(100 1875);
DISPLAY 0.617021 (100 1875);
PAINT BLUE (100 1875);
FORCEPROP 1 LAST VALUE 47UF
J 0
(100 2075);
DISPLAY 0.617021 (100 2075);
PAINT SKYBLUE (100 2075);
FORCEPROP 1 LAST TOLERANCE 20%
J 0
(100 1975);
DISPLAY 0.617021 (100 1975);
PAINT SKYBLUE (100 1975);
FORCEPROP 1 LAST PACK_TYPE 0805
J 0
(100 1825);
DISPLAY 0.617021 (100 1825);
PAINT SKYBLUE (100 1825);
FORCEPROP 1 LAST VOLTAGE 4V
J 0
(100 2025);
DISPLAY 0.617021 (100 2025);
PAINT SKYBLUE (100 2025);
FORCEPROP 1 LAST MATERIAL X6S
J 0
(100 1925);
DISPLAY 0.617021 (100 1925);
PAINT SKYBLUE (100 1925);
FORCEPROP 1 LASTPIN (50 1925) $PN 2
J 0
(60 1905);
DISPLAY 0.617021 (60 1905);
PAINT WHITE (60 1905);
FORCEPROP 1 LASTPIN (50 2125) $PN 1
J 0
(60 2105);
DISPLAY 0.617021 (60 2105);
PAINT WHITE (60 2105);
FORCEPROP 2 LAST BOM_COST SB
J 0
(100 2225);
DISPLAY 1.361702 (100 2225);
PAINT ORANGE (100 2225);
DISPLAY INVISIBLE (100 2225);
FORCEPROP 2 LAST CDS_LIB mstr_discrete
J 0
(50 2025);
PAINT MONO (50 2025);
DISPLAY INVISIBLE (50 2025);
FORCEPROP 2 LAST CDS_SEC 1
J 0
(100 2225);
DISPLAY 1.361702 (100 2225);
PAINT ORANGE (100 2225);
DISPLAY INVISIBLE (100 2225);
FORCEPROP 2 LAST $SEC 1
J 0
(100 2225);
DISPLAY 0.914894 (100 2225);
PAINT MONO (100 2225);
DISPLAY INVISIBLE (100 2225);
FORCEPROP 2 LAST CDS_LOCATION C8B16
J 0
(100 2125);
DISPLAY 0.617021 (100 2125);
PAINT AQUA (100 2125);
DISPLAY INVISIBLE (100 2125);
FORCEPROP 1 LAST PATH I22
J 0
(100 2175);
DISPLAY 0.978723 (100 2175);
PAINT WHITE (100 2175);
DISPLAY INVISIBLE (100 2175);
FORCEPROP 2 LAST ROOM SB_DECOUPLING
J 0
(100 2175);
DISPLAY 1.361702 (100 2175);
PAINT ORANGE (100 2175);
DISPLAY INVISIBLE (100 2175);
FORCEADD P1V05_PCH_STBY..1
(-175 2325);
FORCEPROP 3 LASTPIN (-175 2275) SIG_NAME P1V05_PCH_STBY\g
J 0
(-165 2285);
DISPLAY 0.659574 (-165 2285);
PAINT MONO (-165 2285);
DISPLAY INVISIBLE (-165 2285);
FORCEPROP 1 LAST VOLTAGE 1.05V
J 0
(-220 2282);
DISPLAY 0.340426 (-220 2282);
PAINT SKYBLUE (-220 2282);
DISPLAY INVISIBLE (-220 2282);
FORCEPROP 2 LAST BOM_COST SB
J 0
(-175 2425);
DISPLAY 1.361702 (-175 2425);
PAINT ORANGE (-175 2425);
DISPLAY INVISIBLE (-175 2425);
FORCEPROP 2 LAST CDS_LIB mstr_symbols
J 0
(-175 2325);
PAINT ORANGE (-175 2325);
DISPLAY INVISIBLE (-175 2325);
FORCEPROP 1 LAST BODY_TYPE PLUMBING
J 0
(-220 2282);
DISPLAY 0.340426 (-220 2282);
PAINT GREEN (-220 2282);
DISPLAY INVISIBLE (-220 2282);
FORCEPROP 1 LAST PATH I23
J 0
(-125 2350);
DISPLAY 0.872340 (-125 2350);
PAINT AQUA (-125 2350);
DISPLAY INVISIBLE (-125 2350);
FORCEPROP 2 LAST ROOM SB_DECOUPLING
J 0
(-175 2425);
DISPLAY 1.361702 (-175 2425);
PAINT ORANGE (-175 2425);
DISPLAY INVISIBLE (-175 2425);
FORCEPROP 1 LAST HDL_POWER P1V05_PCH_STBY
J 0
(-175 2375);
DISPLAY 0.872340 (-175 2375);
PAINT GREEN (-175 2375);
DISPLAY INVISIBLE (-175 2375);
FORCEADD CAP..1
(-400 2025);
FORCEPROP 1 LAST LOCATION C8B15
J 0
(-350 2125);
DISPLAY 0.617021 (-350 2125);
PAINT AQUA (-350 2125);
FORCEPROP 1 LAST PART_NUMBER C95333-006
J 0
(-350 1875);
DISPLAY 0.617021 (-350 1875);
PAINT BLUE (-350 1875);
FORCEPROP 1 LAST VALUE 47UF
J 0
(-350 2075);
DISPLAY 0.617021 (-350 2075);
PAINT SKYBLUE (-350 2075);
FORCEPROP 1 LAST TOLERANCE 20%
J 0
(-350 1975);
DISPLAY 0.617021 (-350 1975);
PAINT SKYBLUE (-350 1975);
FORCEPROP 1 LAST PACK_TYPE 0805
J 0
(-350 1825);
DISPLAY 0.617021 (-350 1825);
PAINT SKYBLUE (-350 1825);
FORCEPROP 1 LAST VOLTAGE 4V
J 0
(-350 2025);
DISPLAY 0.617021 (-350 2025);
PAINT SKYBLUE (-350 2025);
FORCEPROP 1 LAST MATERIAL X6S
J 0
(-350 1925);
DISPLAY 0.617021 (-350 1925);
PAINT SKYBLUE (-350 1925);
FORCEPROP 1 LASTPIN (-400 1925) $PN 2
J 0
(-390 1905);
DISPLAY 0.617021 (-390 1905);
PAINT WHITE (-390 1905);
FORCEPROP 1 LASTPIN (-400 2125) $PN 1
J 0
(-390 2105);
DISPLAY 0.617021 (-390 2105);
PAINT WHITE (-390 2105);
FORCEPROP 2 LAST BOM_COST SB
J 0
(-350 2225);
DISPLAY 1.361702 (-350 2225);
PAINT ORANGE (-350 2225);
DISPLAY INVISIBLE (-350 2225);
FORCEPROP 2 LAST CDS_LIB mstr_discrete
J 0
(-400 2025);
PAINT MONO (-400 2025);
DISPLAY INVISIBLE (-400 2025);
FORCEPROP 2 LAST CDS_SEC 1
J 0
(-350 2225);
DISPLAY 1.361702 (-350 2225);
PAINT ORANGE (-350 2225);
DISPLAY INVISIBLE (-350 2225);
FORCEPROP 2 LAST $SEC 1
J 0
(-350 2225);
DISPLAY 0.914894 (-350 2225);
PAINT MONO (-350 2225);
DISPLAY INVISIBLE (-350 2225);
FORCEPROP 2 LAST CDS_LOCATION C8B15
J 0
(-350 2125);
DISPLAY 0.617021 (-350 2125);
PAINT AQUA (-350 2125);
DISPLAY INVISIBLE (-350 2125);
FORCEPROP 1 LAST PATH I24
J 0
(-350 2175);
DISPLAY 0.978723 (-350 2175);
PAINT WHITE (-350 2175);
DISPLAY INVISIBLE (-350 2175);
FORCEPROP 2 LAST ROOM SB_DECOUPLING
J 0
(-350 2175);
DISPLAY 1.361702 (-350 2175);
PAINT ORANGE (-350 2175);
DISPLAY INVISIBLE (-350 2175);
FORCEADD GND..1
(-175 1650);
FORCEPROP 3 LASTPIN (-175 1700) SIG_NAME GND\g
J 0
(-165 1710);
DISPLAY 0.659574 (-165 1710);
PAINT MONO (-165 1710);
DISPLAY INVISIBLE (-165 1710);
FORCEPROP 1 LAST VOLTAGE 0.0V
J 0
(-220 1607);
DISPLAY 0.340426 (-220 1607);
PAINT SKYBLUE (-220 1607);
DISPLAY INVISIBLE (-220 1607);
FORCEPROP 1 LAST SIZE 1B
J 0
(-100 1600);
DISPLAY 1.170213 (-100 1600);
PAINT AQUA (-100 1600);
DISPLAY INVISIBLE (-100 1600);
FORCEPROP 2 LAST CDS_LIB mstr_symbols
J 0
(-175 1650);
PAINT MONO (-175 1650);
DISPLAY INVISIBLE (-175 1650);
FORCEPROP 2 LAST BOM_COST SB
J 0
(-150 1725);
DISPLAY 1.361702 (-150 1725);
PAINT ORANGE (-150 1725);
DISPLAY INVISIBLE (-150 1725);
FORCEPROP 1 LAST BODY_TYPE PLUMBING
J 0
(-220 1607);
DISPLAY 0.340426 (-220 1607);
PAINT GREEN (-220 1607);
DISPLAY INVISIBLE (-220 1607);
FORCEPROP 1 LAST PATH I25
J 0
(-100 1650);
DISPLAY 0.872340 (-100 1650);
PAINT AQUA (-100 1650);
DISPLAY INVISIBLE (-100 1650);
FORCEPROP 2 LAST ROOM SB_DECOUPLING
J 0
(-150 1725);
DISPLAY 1.361702 (-150 1725);
PAINT ORANGE (-150 1725);
DISPLAY INVISIBLE (-150 1725);
FORCEPROP 1 LAST HDL_POWER GND
J 0
(-175 1800);
DISPLAY 1.170213 (-175 1800);
PAINT GREEN (-175 1800);
DISPLAY INVISIBLE (-175 1800);
FORCEADD P1V05_PCH_STBY..1
(-4575 5000);
FORCEPROP 3 LASTPIN (-4575 4950) SIG_NAME P1V05_PCH_STBY\g
J 0
(-4565 4960);
DISPLAY 0.659574 (-4565 4960);
PAINT MONO (-4565 4960);
DISPLAY INVISIBLE (-4565 4960);
FORCEPROP 1 LAST VOLTAGE 1.05V
J 0
(-4620 4957);
DISPLAY 0.340426 (-4620 4957);
PAINT SKYBLUE (-4620 4957);
DISPLAY INVISIBLE (-4620 4957);
FORCEPROP 2 LAST BOM_COST SB
J 0
(-4575 5150);
PAINT MONO (-4575 5150);
DISPLAY INVISIBLE (-4575 5150);
FORCEPROP 2 LAST CDS_LIB mstr_symbols
J 0
(-4575 5000);
PAINT ORANGE (-4575 5000);
DISPLAY INVISIBLE (-4575 5000);
FORCEPROP 1 LAST BODY_TYPE PLUMBING
J 0
(-4620 4957);
DISPLAY 0.340426 (-4620 4957);
PAINT GREEN (-4620 4957);
DISPLAY INVISIBLE (-4620 4957);
FORCEPROP 1 LAST PATH I26
J 0
(-4525 5025);
DISPLAY 0.872340 (-4525 5025);
PAINT AQUA (-4525 5025);
DISPLAY INVISIBLE (-4525 5025);
FORCEPROP 2 LAST ROOM SB_DECOUPLING
J 0
(-4575 5100);
DISPLAY 1.361702 (-4575 5100);
PAINT WHITE (-4575 5100);
DISPLAY INVISIBLE (-4575 5100);
FORCEPROP 1 LAST HDL_POWER P1V05_PCH_STBY
J 0
(-4575 5050);
DISPLAY 0.872340 (-4575 5050);
PAINT GREEN (-4575 5050);
DISPLAY INVISIBLE (-4575 5050);
FORCEADD CAP_A..1
(-2375 4725);
FORCEPROP 1 LAST LOCATION C2M22
J 0
(-2325 4825);
DISPLAY 0.617021 (-2325 4825);
PAINT AQUA (-2325 4825);
FORCEPROP 1 LAST PART_NUMBER D97712-004
J 0
(-2325 4575);
DISPLAY 0.617021 (-2325 4575);
PAINT BLUE (-2325 4575);
FORCEPROP 1 LAST VALUE 1.0UF
J 0
(-2325 4775);
DISPLAY 0.617021 (-2325 4775);
PAINT SKYBLUE (-2325 4775);
FORCEPROP 1 LAST TOLERANCE 10%
J 0
(-2325 4675);
DISPLAY 0.617021 (-2325 4675);
PAINT SKYBLUE (-2325 4675);
FORCEPROP 1 LAST PACK_TYPE 0402V
J 0
(-2325 4525);
DISPLAY 0.617021 (-2325 4525);
PAINT SKYBLUE (-2325 4525);
FORCEPROP 1 LAST VOLTAGE 6.3V
J 0
(-2325 4725);
DISPLAY 0.617021 (-2325 4725);
PAINT SKYBLUE (-2325 4725);
FORCEPROP 1 LAST MATERIAL X6S
J 0
(-2325 4625);
DISPLAY 0.617021 (-2325 4625);
PAINT SKYBLUE (-2325 4625);
FORCEPROP 1 LASTPIN (-2375 4825) $PN 1
J 0
(-2365 4805);
DISPLAY 0.617021 (-2365 4805);
PAINT ORANGE (-2365 4805);
FORCEPROP 1 LASTPIN (-2375 4625) $PN 2
J 0
(-2365 4605);
DISPLAY 0.617021 (-2365 4605);
PAINT ORANGE (-2365 4605);
FORCEPROP 2 LAST CDS_LOCATION C2M22
J 0
(-2325 4825);
DISPLAY 0.617021 (-2325 4825);
PAINT AQUA (-2325 4825);
DISPLAY INVISIBLE (-2325 4825);
FORCEPROP 2 LAST BOM_COST SB
J 0
(-2325 4475);
PAINT MONO (-2325 4475);
DISPLAY INVISIBLE (-2325 4475);
FORCEPROP 2 LAST CDS_LIB dev_discrete
J 0
(-2375 4725);
PAINT ORANGE (-2375 4725);
DISPLAY INVISIBLE (-2375 4725);
FORCEPROP 2 LAST CDS_SEC 1
J 0
(-2325 4925);
PAINT MONO (-2325 4925);
DISPLAY INVISIBLE (-2325 4925);
FORCEPROP 2 LAST $SEC 1
J 0
(-2325 4925);
PAINT MONO (-2325 4925);
DISPLAY INVISIBLE (-2325 4925);
FORCEPROP 1 LAST PATH I27
J 0
(-2325 4875);
DISPLAY 0.978723 (-2325 4875);
PAINT WHITE (-2325 4875);
DISPLAY INVISIBLE (-2325 4875);
FORCEPROP 2 LAST ROOM SB_DECOUPLING
J 0
(-2375 4725);
PAINT WHITE (-2375 4725);
DISPLAY INVISIBLE (-2375 4725);
FORCEADD CAP_A..1
(-2800 4725);
FORCEPROP 1 LAST LOCATION C2M21
J 0
(-2750 4825);
DISPLAY 0.617021 (-2750 4825);
PAINT AQUA (-2750 4825);
FORCEPROP 1 LAST PART_NUMBER D97712-004
J 0
(-2750 4575);
DISPLAY 0.617021 (-2750 4575);
PAINT BLUE (-2750 4575);
FORCEPROP 1 LAST VALUE 1.0UF
J 0
(-2750 4775);
DISPLAY 0.617021 (-2750 4775);
PAINT SKYBLUE (-2750 4775);
FORCEPROP 1 LAST TOLERANCE 10%
J 0
(-2750 4675);
DISPLAY 0.617021 (-2750 4675);
PAINT SKYBLUE (-2750 4675);
FORCEPROP 1 LAST PACK_TYPE 0402V
J 0
(-2750 4525);
DISPLAY 0.617021 (-2750 4525);
PAINT SKYBLUE (-2750 4525);
FORCEPROP 1 LAST VOLTAGE 6.3V
J 0
(-2750 4725);
DISPLAY 0.617021 (-2750 4725);
PAINT SKYBLUE (-2750 4725);
FORCEPROP 1 LAST MATERIAL X6S
J 0
(-2750 4625);
DISPLAY 0.617021 (-2750 4625);
PAINT SKYBLUE (-2750 4625);
FORCEPROP 1 LASTPIN (-2800 4825) $PN 1
J 0
(-2790 4805);
DISPLAY 0.617021 (-2790 4805);
PAINT WHITE (-2790 4805);
FORCEPROP 1 LASTPIN (-2800 4625) $PN 2
J 0
(-2790 4605);
DISPLAY 0.617021 (-2790 4605);
PAINT WHITE (-2790 4605);
FORCEPROP 2 LAST CDS_LOCATION C2M21
J 0
(-2750 4825);
DISPLAY 0.617021 (-2750 4825);
PAINT AQUA (-2750 4825);
DISPLAY INVISIBLE (-2750 4825);
FORCEPROP 0 LAST BOM_COST SB
J 0
(-2750 5025);
DISPLAY 1.021277 (-2750 5025);
PAINT ORANGE (-2750 5025);
DISPLAY INVISIBLE (-2750 5025);
FORCEPROP 2 LAST CDS_LIB dev_discrete
J 0
(-2800 4725);
PAINT ORANGE (-2800 4725);
DISPLAY INVISIBLE (-2800 4725);
FORCEPROP 2 LAST CDS_SEC 1
J 0
(-2750 4925);
PAINT MONO (-2750 4925);
DISPLAY INVISIBLE (-2750 4925);
FORCEPROP 2 LAST $SEC 1
J 0
(-2750 4925);
DISPLAY 0.914894 (-2750 4925);
PAINT MONO (-2750 4925);
DISPLAY INVISIBLE (-2750 4925);
FORCEPROP 1 LAST PATH I28
J 0
(-2750 4875);
DISPLAY 0.978723 (-2750 4875);
PAINT WHITE (-2750 4875);
DISPLAY INVISIBLE (-2750 4875);
FORCEPROP 0 LAST ROOM SB_DECOUPLING
J 0
(-2750 4925);
DISPLAY 1.021277 (-2750 4925);
PAINT ORANGE (-2750 4925);
DISPLAY INVISIBLE (-2750 4925);
FORCEADD CAP_A..1
(-3175 4725);
FORCEPROP 1 LAST LOCATION C2M18
J 0
(-3125 4825);
DISPLAY 0.617021 (-3125 4825);
PAINT AQUA (-3125 4825);
FORCEPROP 1 LAST PART_NUMBER D97712-004
J 0
(-3125 4575);
DISPLAY 0.617021 (-3125 4575);
PAINT BLUE (-3125 4575);
FORCEPROP 1 LAST VALUE 1.0UF
J 0
(-3125 4775);
DISPLAY 0.617021 (-3125 4775);
PAINT SKYBLUE (-3125 4775);
FORCEPROP 1 LAST TOLERANCE 10%
J 0
(-3125 4675);
DISPLAY 0.617021 (-3125 4675);
PAINT SKYBLUE (-3125 4675);
FORCEPROP 1 LAST PACK_TYPE 0402V
J 0
(-3125 4525);
DISPLAY 0.617021 (-3125 4525);
PAINT SKYBLUE (-3125 4525);
FORCEPROP 1 LAST VOLTAGE 6.3V
J 0
(-3125 4725);
DISPLAY 0.617021 (-3125 4725);
PAINT SKYBLUE (-3125 4725);
FORCEPROP 1 LAST MATERIAL X6S
J 0
(-3125 4625);
DISPLAY 0.617021 (-3125 4625);
PAINT SKYBLUE (-3125 4625);
FORCEPROP 1 LASTPIN (-3175 4825) $PN 1
J 0
(-3165 4805);
DISPLAY 0.617021 (-3165 4805);
PAINT WHITE (-3165 4805);
FORCEPROP 1 LASTPIN (-3175 4625) $PN 2
J 0
(-3165 4605);
DISPLAY 0.617021 (-3165 4605);
PAINT WHITE (-3165 4605);
FORCEPROP 2 LAST CDS_LOCATION C2M18
J 0
(-3125 4825);
DISPLAY 0.617021 (-3125 4825);
PAINT AQUA (-3125 4825);
DISPLAY INVISIBLE (-3125 4825);
FORCEPROP 2 LAST BOM_COST SB
J 0
(-3125 4475);
PAINT MONO (-3125 4475);
DISPLAY INVISIBLE (-3125 4475);
FORCEPROP 2 LAST CDS_LIB dev_discrete
J 0
(-3175 4725);
PAINT ORANGE (-3175 4725);
DISPLAY INVISIBLE (-3175 4725);
FORCEPROP 2 LAST CDS_SEC 1
J 0
(-3125 4925);
DISPLAY 1.361702 (-3125 4925);
PAINT ORANGE (-3125 4925);
DISPLAY INVISIBLE (-3125 4925);
FORCEPROP 2 LAST $SEC 1
J 0
(-3125 4925);
DISPLAY 0.914894 (-3125 4925);
PAINT MONO (-3125 4925);
DISPLAY INVISIBLE (-3125 4925);
FORCEPROP 1 LAST PATH I29
J 0
(-3125 4875);
DISPLAY 0.978723 (-3125 4875);
PAINT WHITE (-3125 4875);
DISPLAY INVISIBLE (-3125 4875);
FORCEPROP 2 LAST ROOM SB_DECOUPLING
J 0
(-3175 4725);
PAINT WHITE (-3175 4725);
DISPLAY INVISIBLE (-3175 4725);
FORCEADD CAP_A..1
(50 4975);
FORCEPROP 1 LAST LOCATION C7B16
J 0
(100 5075);
DISPLAY 0.617021 (100 5075);
PAINT AQUA (100 5075);
FORCEPROP 1 LAST PART_NUMBER E15431-004
J 0
(100 4825);
DISPLAY 0.617021 (100 4825);
PAINT BLUE (100 4825);
FORCEPROP 1 LAST VALUE 22.0UF
J 0
(100 5025);
DISPLAY 0.617021 (100 5025);
PAINT SKYBLUE (100 5025);
FORCEPROP 1 LAST TOLERANCE 20%
J 0
(100 4925);
DISPLAY 0.617021 (100 4925);
PAINT SKYBLUE (100 4925);
FORCEPROP 1 LAST PACK_TYPE 0603V
J 0
(100 4775);
DISPLAY 0.617021 (100 4775);
PAINT SKYBLUE (100 4775);
FORCEPROP 1 LAST VOLTAGE 4V
J 0
(100 4975);
DISPLAY 0.617021 (100 4975);
PAINT SKYBLUE (100 4975);
FORCEPROP 1 LAST MATERIAL X6S
J 0
(100 4875);
DISPLAY 0.617021 (100 4875);
PAINT SKYBLUE (100 4875);
FORCEPROP 2 LAST CDS_LOCATION C7B16
J 0
(100 5075);
DISPLAY 0.617021 (100 5075);
PAINT AQUA (100 5075);
DISPLAY INVISIBLE (100 5075);
FORCEPROP 2 LAST BOM_COST SB
J 0
(100 4725);
PAINT MONO (100 4725);
DISPLAY INVISIBLE (100 4725);
FORCEPROP 2 LAST CDS_LIB dev_discrete
J 0
(50 4975);
PAINT ORANGE (50 4975);
DISPLAY INVISIBLE (50 4975);
FORCEPROP 2 LAST CDS_SEC 1
J 0
(100 5175);
DISPLAY 1.361702 (100 5175);
PAINT ORANGE (100 5175);
DISPLAY INVISIBLE (100 5175);
FORCEPROP 2 LAST $SEC 1
J 0
(100 5175);
DISPLAY 0.914894 (100 5175);
PAINT MONO (100 5175);
DISPLAY INVISIBLE (100 5175);
FORCEPROP 1 LAST PATH I3
J 0
(100 5125);
DISPLAY 0.978723 (100 5125);
PAINT WHITE (100 5125);
DISPLAY INVISIBLE (100 5125);
FORCEPROP 2 LAST ROOM SB_DECOUPLING
J 0
(50 4975);
PAINT WHITE (50 4975);
DISPLAY INVISIBLE (50 4975);
FORCEPROP 1 LASTPIN (50 5075) $PN 1
J 0
(60 5055);
DISPLAY 1.063830 (60 5055);
PAINT WHITE (60 5055);
DISPLAY INVISIBLE (60 5055);
FORCEPROP 1 LASTPIN (50 4875) $PN 2
J 0
(60 4855);
DISPLAY 1.063830 (60 4855);
PAINT WHITE (60 4855);
DISPLAY INVISIBLE (60 4855);
FORCEADD GND..1
(-3350 4375);
FORCEPROP 3 LASTPIN (-3350 4425) SIG_NAME GND\g
J 0
(-3340 4435);
DISPLAY 0.659574 (-3340 4435);
PAINT MONO (-3340 4435);
DISPLAY INVISIBLE (-3340 4435);
FORCEPROP 1 LAST VOLTAGE 0
J 0
(-3350 4375);
PAINT SKYBLUE (-3350 4375);
DISPLAY INVISIBLE (-3350 4375);
FORCEPROP 2 LAST BOM_COST SB
J 0
(-3400 4450);
PAINT MONO (-3400 4450);
DISPLAY INVISIBLE (-3400 4450);
FORCEPROP 1 LAST SIZE 1B
J 0
(-3275 4325);
DISPLAY 1.404255 (-3275 4325);
PAINT GREEN (-3275 4325);
DISPLAY INVISIBLE (-3275 4325);
FORCEPROP 2 LAST CDS_LIB mstr_symbols
J 0
(-3350 4375);
PAINT ORANGE (-3350 4375);
DISPLAY INVISIBLE (-3350 4375);
FORCEPROP 1 LAST BODY_TYPE PLUMBING
J 0
(-3395 4332);
DISPLAY 0.340426 (-3395 4332);
PAINT GREEN (-3395 4332);
DISPLAY INVISIBLE (-3395 4332);
FORCEPROP 1 LAST PATH I30
J 0
(-3275 4375);
DISPLAY 0.872340 (-3275 4375);
PAINT AQUA (-3275 4375);
DISPLAY INVISIBLE (-3275 4375);
FORCEPROP 2 LAST ROOM SB_DECOUPLING
J 0
(-3825 4450);
PAINT WHITE (-3825 4450);
DISPLAY INVISIBLE (-3825 4450);
FORCEPROP 1 LAST HDL_POWER GND
J 0
(-3350 4525);
DISPLAY 1.404255 (-3350 4525);
PAINT GREEN (-3350 4525);
DISPLAY INVISIBLE (-3350 4525);
FORCEADD CAP_A..1
(-2850 3525);
FORCEPROP 1 LAST LOCATION C2M19
J 0
(-2800 3625);
DISPLAY 0.617021 (-2800 3625);
PAINT AQUA (-2800 3625);
FORCEPROP 1 LAST PART_NUMBER D97712-004
J 0
(-2800 3375);
DISPLAY 0.617021 (-2800 3375);
PAINT BLUE (-2800 3375);
FORCEPROP 1 LAST VALUE 1.0UF
J 0
(-2800 3575);
DISPLAY 0.617021 (-2800 3575);
PAINT SKYBLUE (-2800 3575);
FORCEPROP 1 LAST TOLERANCE 10%
J 0
(-2800 3475);
DISPLAY 0.617021 (-2800 3475);
PAINT SKYBLUE (-2800 3475);
FORCEPROP 1 LAST PACK_TYPE 0402V
J 0
(-2800 3325);
DISPLAY 0.617021 (-2800 3325);
PAINT SKYBLUE (-2800 3325);
FORCEPROP 1 LAST VOLTAGE 6.3V
J 0
(-2800 3525);
DISPLAY 0.617021 (-2800 3525);
PAINT SKYBLUE (-2800 3525);
FORCEPROP 1 LAST MATERIAL X6S
J 0
(-2800 3425);
DISPLAY 0.617021 (-2800 3425);
PAINT SKYBLUE (-2800 3425);
FORCEPROP 1 LASTPIN (-2850 3625) $PN 1
J 0
(-2840 3605);
DISPLAY 0.617021 (-2840 3605);
PAINT WHITE (-2840 3605);
FORCEPROP 1 LASTPIN (-2850 3425) $PN 2
J 0
(-2840 3405);
DISPLAY 0.617021 (-2840 3405);
PAINT WHITE (-2840 3405);
FORCEPROP 2 LAST CDS_LOCATION C2M19
J 0
(-2800 3625);
DISPLAY 0.617021 (-2800 3625);
PAINT AQUA (-2800 3625);
DISPLAY INVISIBLE (-2800 3625);
FORCEPROP 2 LAST BOM_COST SB
J 0
(-2800 3275);
PAINT MONO (-2800 3275);
DISPLAY INVISIBLE (-2800 3275);
FORCEPROP 2 LAST CDS_LIB dev_discrete
J 0
(-2850 3525);
PAINT ORANGE (-2850 3525);
DISPLAY INVISIBLE (-2850 3525);
FORCEPROP 2 LAST CDS_SEC 1
J 0
(-2800 3725);
DISPLAY 1.361702 (-2800 3725);
PAINT ORANGE (-2800 3725);
DISPLAY INVISIBLE (-2800 3725);
FORCEPROP 2 LAST $SEC 1
J 0
(-2800 3725);
DISPLAY 0.914894 (-2800 3725);
PAINT MONO (-2800 3725);
DISPLAY INVISIBLE (-2800 3725);
FORCEPROP 1 LAST PATH I31
J 0
(-2800 3675);
DISPLAY 0.978723 (-2800 3675);
PAINT WHITE (-2800 3675);
DISPLAY INVISIBLE (-2800 3675);
FORCEPROP 2 LAST ROOM SB_DECOUPLING
J 0
(-2850 3525);
PAINT WHITE (-2850 3525);
DISPLAY INVISIBLE (-2850 3525);
FORCEADD CAP_A..1
(-3225 3525);
FORCEPROP 1 LAST LOCATION C3M38
J 0
(-3175 3625);
DISPLAY 0.617021 (-3175 3625);
PAINT AQUA (-3175 3625);
FORCEPROP 1 LAST PART_NUMBER D97712-004
J 0
(-3175 3375);
DISPLAY 0.617021 (-3175 3375);
PAINT BLUE (-3175 3375);
FORCEPROP 1 LAST VALUE 1.0UF
J 0
(-3175 3575);
DISPLAY 0.617021 (-3175 3575);
PAINT SKYBLUE (-3175 3575);
FORCEPROP 1 LAST TOLERANCE 10%
J 0
(-3175 3475);
DISPLAY 0.617021 (-3175 3475);
PAINT SKYBLUE (-3175 3475);
FORCEPROP 1 LAST PACK_TYPE 0402V
J 0
(-3175 3325);
DISPLAY 0.617021 (-3175 3325);
PAINT SKYBLUE (-3175 3325);
FORCEPROP 1 LAST VOLTAGE 6.3V
J 0
(-3175 3525);
DISPLAY 0.617021 (-3175 3525);
PAINT SKYBLUE (-3175 3525);
FORCEPROP 1 LAST MATERIAL X6S
J 0
(-3175 3425);
DISPLAY 0.617021 (-3175 3425);
PAINT SKYBLUE (-3175 3425);
FORCEPROP 1 LASTPIN (-3225 3625) $PN 1
J 0
(-3215 3605);
DISPLAY 0.617021 (-3215 3605);
PAINT WHITE (-3215 3605);
FORCEPROP 1 LASTPIN (-3225 3425) $PN 2
J 0
(-3215 3405);
DISPLAY 0.617021 (-3215 3405);
PAINT WHITE (-3215 3405);
FORCEPROP 2 LAST CDS_LOCATION C3M38
J 0
(-3175 3625);
DISPLAY 0.617021 (-3175 3625);
PAINT AQUA (-3175 3625);
DISPLAY INVISIBLE (-3175 3625);
FORCEPROP 2 LAST BOM_COST SB
J 0
(-3175 3275);
PAINT MONO (-3175 3275);
DISPLAY INVISIBLE (-3175 3275);
FORCEPROP 2 LAST CDS_LIB dev_discrete
J 0
(-3225 3525);
PAINT ORANGE (-3225 3525);
DISPLAY INVISIBLE (-3225 3525);
FORCEPROP 2 LAST CDS_SEC 1
J 0
(-3175 3725);
DISPLAY 1.361702 (-3175 3725);
PAINT ORANGE (-3175 3725);
DISPLAY INVISIBLE (-3175 3725);
FORCEPROP 2 LAST $SEC 1
J 0
(-3175 3725);
DISPLAY 0.914894 (-3175 3725);
PAINT MONO (-3175 3725);
DISPLAY INVISIBLE (-3175 3725);
FORCEPROP 1 LAST PATH I32
J 0
(-3175 3675);
DISPLAY 0.978723 (-3175 3675);
PAINT WHITE (-3175 3675);
DISPLAY INVISIBLE (-3175 3675);
FORCEPROP 2 LAST ROOM SB_DECOUPLING
J 0
(-3225 3525);
PAINT WHITE (-3225 3525);
DISPLAY INVISIBLE (-3225 3525);
FORCEADD GND..1
(-3425 3175);
FORCEPROP 3 LASTPIN (-3425 3225) SIG_NAME GND\g
J 0
(-3415 3235);
DISPLAY 0.659574 (-3415 3235);
PAINT MONO (-3415 3235);
DISPLAY INVISIBLE (-3415 3235);
FORCEPROP 1 LAST VOLTAGE 0
J 0
(-3425 3175);
PAINT SKYBLUE (-3425 3175);
DISPLAY INVISIBLE (-3425 3175);
FORCEPROP 1 LAST SIZE 1B
J 0
(-3350 3125);
DISPLAY 1.404255 (-3350 3125);
PAINT GREEN (-3350 3125);
DISPLAY INVISIBLE (-3350 3125);
FORCEPROP 2 LAST CDS_LIB mstr_symbols
J 0
(-3425 3175);
PAINT ORANGE (-3425 3175);
DISPLAY INVISIBLE (-3425 3175);
FORCEPROP 2 LAST BOM_COST SB
J 0
(-3475 3250);
PAINT MONO (-3475 3250);
DISPLAY INVISIBLE (-3475 3250);
FORCEPROP 1 LAST BODY_TYPE PLUMBING
J 0
(-3470 3132);
DISPLAY 0.340426 (-3470 3132);
PAINT GREEN (-3470 3132);
DISPLAY INVISIBLE (-3470 3132);
FORCEPROP 1 LAST PATH I33
J 0
(-3350 3175);
DISPLAY 0.872340 (-3350 3175);
PAINT AQUA (-3350 3175);
DISPLAY INVISIBLE (-3350 3175);
FORCEPROP 2 LAST ROOM SB_DECOUPLING
J 0
(-3900 3250);
PAINT WHITE (-3900 3250);
DISPLAY INVISIBLE (-3900 3250);
FORCEPROP 1 LAST HDL_POWER GND
J 0
(-3425 3325);
DISPLAY 1.404255 (-3425 3325);
PAINT GREEN (-3425 3325);
DISPLAY INVISIBLE (-3425 3325);
FORCEADD CAP..1
(-2400 2025);
FORCEPROP 1 LAST LOCATION C2M17
J 0
(-2350 2125);
DISPLAY 0.617021 (-2350 2125);
PAINT AQUA (-2350 2125);
FORCEPROP 1 LAST PART_NUMBER C95333-006
J 0
(-2350 1875);
DISPLAY 0.617021 (-2350 1875);
PAINT BLUE (-2350 1875);
FORCEPROP 1 LAST VALUE 47UF
J 0
(-2350 2075);
DISPLAY 0.617021 (-2350 2075);
PAINT SKYBLUE (-2350 2075);
FORCEPROP 1 LAST TOLERANCE 20%
J 0
(-2350 1975);
DISPLAY 0.617021 (-2350 1975);
PAINT SKYBLUE (-2350 1975);
FORCEPROP 1 LAST PACK_TYPE 0805
J 0
(-2350 1825);
DISPLAY 0.617021 (-2350 1825);
PAINT SKYBLUE (-2350 1825);
FORCEPROP 1 LAST VOLTAGE 4V
J 0
(-2350 2025);
DISPLAY 0.617021 (-2350 2025);
PAINT SKYBLUE (-2350 2025);
FORCEPROP 1 LAST MATERIAL X6S
J 0
(-2350 1925);
DISPLAY 0.617021 (-2350 1925);
PAINT SKYBLUE (-2350 1925);
FORCEPROP 1 LASTPIN (-2400 1925) $PN 2
J 0
(-2390 1905);
DISPLAY 0.617021 (-2390 1905);
PAINT ORANGE (-2390 1905);
FORCEPROP 1 LASTPIN (-2400 2125) $PN 1
J 0
(-2390 2105);
DISPLAY 0.617021 (-2390 2105);
PAINT ORANGE (-2390 2105);
FORCEPROP 2 LAST CDS_LIB mstr_discrete
J 0
(-2400 2025);
PAINT ORANGE (-2400 2025);
DISPLAY INVISIBLE (-2400 2025);
FORCEPROP 2 LAST BOM_COST SB
J 0
(-2350 2225);
DISPLAY 1.361702 (-2350 2225);
PAINT ORANGE (-2350 2225);
DISPLAY INVISIBLE (-2350 2225);
FORCEPROP 2 LAST CDS_SEC 1
J 0
(-2350 2225);
DISPLAY 1.361702 (-2350 2225);
PAINT ORANGE (-2350 2225);
DISPLAY INVISIBLE (-2350 2225);
FORCEPROP 2 LAST $SEC 1
J 0
(-2350 2225);
DISPLAY 0.914894 (-2350 2225);
PAINT MONO (-2350 2225);
DISPLAY INVISIBLE (-2350 2225);
FORCEPROP 2 LAST CDS_LOCATION C2M17
J 0
(-2350 2125);
DISPLAY 0.617021 (-2350 2125);
PAINT AQUA (-2350 2125);
DISPLAY INVISIBLE (-2350 2125);
FORCEPROP 1 LAST PATH I34
J 0
(-2350 2175);
DISPLAY 0.978723 (-2350 2175);
PAINT WHITE (-2350 2175);
DISPLAY INVISIBLE (-2350 2175);
FORCEPROP 2 LAST ROOM SB_DECOUPLING
J 0
(-2350 2175);
DISPLAY 1.361702 (-2350 2175);
PAINT ORANGE (-2350 2175);
DISPLAY INVISIBLE (-2350 2175);
FORCEADD CAP..1
(-2800 2025);
FORCEPROP 1 LAST LOCATION C2M11
J 0
(-2750 2125);
DISPLAY 0.617021 (-2750 2125);
PAINT AQUA (-2750 2125);
FORCEPROP 1 LAST PART_NUMBER C95333-006
J 0
(-2750 1875);
DISPLAY 0.617021 (-2750 1875);
PAINT BLUE (-2750 1875);
FORCEPROP 1 LAST VALUE 47UF
J 0
(-2750 2075);
DISPLAY 0.617021 (-2750 2075);
PAINT SKYBLUE (-2750 2075);
FORCEPROP 1 LAST TOLERANCE 20%
J 0
(-2750 1975);
DISPLAY 0.617021 (-2750 1975);
PAINT SKYBLUE (-2750 1975);
FORCEPROP 1 LAST PACK_TYPE 0805
J 0
(-2750 1825);
DISPLAY 0.617021 (-2750 1825);
PAINT SKYBLUE (-2750 1825);
FORCEPROP 1 LAST VOLTAGE 4V
J 0
(-2750 2025);
DISPLAY 0.617021 (-2750 2025);
PAINT SKYBLUE (-2750 2025);
FORCEPROP 1 LAST MATERIAL X6S
J 0
(-2750 1925);
DISPLAY 0.617021 (-2750 1925);
PAINT SKYBLUE (-2750 1925);
FORCEPROP 1 LASTPIN (-2800 1925) $PN 2
J 0
(-2790 1905);
DISPLAY 0.617021 (-2790 1905);
PAINT WHITE (-2790 1905);
FORCEPROP 1 LASTPIN (-2800 2125) $PN 1
J 0
(-2790 2105);
DISPLAY 0.617021 (-2790 2105);
PAINT WHITE (-2790 2105);
FORCEPROP 2 LAST BOM_COST SB
J 0
(-2750 2225);
DISPLAY 1.361702 (-2750 2225);
PAINT ORANGE (-2750 2225);
DISPLAY INVISIBLE (-2750 2225);
FORCEPROP 2 LAST CDS_LIB mstr_discrete
J 0
(-2800 2025);
PAINT MONO (-2800 2025);
DISPLAY INVISIBLE (-2800 2025);
FORCEPROP 2 LAST CDS_SEC 1
J 0
(-2750 2225);
DISPLAY 1.361702 (-2750 2225);
PAINT ORANGE (-2750 2225);
DISPLAY INVISIBLE (-2750 2225);
FORCEPROP 2 LAST $SEC 1
J 0
(-2750 2225);
DISPLAY 0.914894 (-2750 2225);
PAINT MONO (-2750 2225);
DISPLAY INVISIBLE (-2750 2225);
FORCEPROP 2 LAST CDS_LOCATION C2M11
J 0
(-2750 2125);
DISPLAY 0.617021 (-2750 2125);
PAINT AQUA (-2750 2125);
DISPLAY INVISIBLE (-2750 2125);
FORCEPROP 1 LAST PATH I35
J 0
(-2750 2175);
DISPLAY 0.978723 (-2750 2175);
PAINT WHITE (-2750 2175);
DISPLAY INVISIBLE (-2750 2175);
FORCEPROP 2 LAST ROOM SB_DECOUPLING
J 0
(-2750 2175);
DISPLAY 1.361702 (-2750 2175);
PAINT ORANGE (-2750 2175);
DISPLAY INVISIBLE (-2750 2175);
FORCEADD P1V05_PCH_STBY..1
(-3025 2325);
FORCEPROP 3 LASTPIN (-3025 2275) SIG_NAME P1V05_PCH_STBY\g
J 0
(-3015 2285);
DISPLAY 0.659574 (-3015 2285);
PAINT MONO (-3015 2285);
DISPLAY INVISIBLE (-3015 2285);
FORCEPROP 1 LAST VOLTAGE 1.05V
J 0
(-3070 2282);
DISPLAY 0.340426 (-3070 2282);
PAINT SKYBLUE (-3070 2282);
DISPLAY INVISIBLE (-3070 2282);
FORCEPROP 2 LAST BOM_COST SB
J 0
(-3025 2425);
DISPLAY 1.361702 (-3025 2425);
PAINT ORANGE (-3025 2425);
DISPLAY INVISIBLE (-3025 2425);
FORCEPROP 2 LAST CDS_LIB mstr_symbols
J 0
(-3025 2325);
PAINT ORANGE (-3025 2325);
DISPLAY INVISIBLE (-3025 2325);
FORCEPROP 1 LAST BODY_TYPE PLUMBING
J 0
(-3070 2282);
DISPLAY 0.340426 (-3070 2282);
PAINT GREEN (-3070 2282);
DISPLAY INVISIBLE (-3070 2282);
FORCEPROP 1 LAST PATH I36
J 0
(-2975 2350);
DISPLAY 0.872340 (-2975 2350);
PAINT AQUA (-2975 2350);
DISPLAY INVISIBLE (-2975 2350);
FORCEPROP 2 LAST ROOM SB_DECOUPLING
J 0
(-3025 2425);
DISPLAY 1.361702 (-3025 2425);
PAINT ORANGE (-3025 2425);
DISPLAY INVISIBLE (-3025 2425);
FORCEPROP 1 LAST HDL_POWER P1V05_PCH_STBY
J 0
(-3025 2375);
DISPLAY 0.872340 (-3025 2375);
PAINT GREEN (-3025 2375);
DISPLAY INVISIBLE (-3025 2375);
FORCEADD CAP..1
(-3250 2025);
FORCEPROP 1 LAST LOCATION C8A13
J 0
(-3200 2125);
DISPLAY 0.617021 (-3200 2125);
PAINT AQUA (-3200 2125);
FORCEPROP 1 LAST PART_NUMBER C95333-006
J 0
(-3200 1875);
DISPLAY 0.617021 (-3200 1875);
PAINT BLUE (-3200 1875);
FORCEPROP 1 LAST VALUE 47UF
J 0
(-3200 2075);
DISPLAY 0.617021 (-3200 2075);
PAINT SKYBLUE (-3200 2075);
FORCEPROP 1 LAST TOLERANCE 20%
J 0
(-3200 1975);
DISPLAY 0.617021 (-3200 1975);
PAINT SKYBLUE (-3200 1975);
FORCEPROP 1 LAST PACK_TYPE 0805
J 0
(-3200 1825);
DISPLAY 0.617021 (-3200 1825);
PAINT SKYBLUE (-3200 1825);
FORCEPROP 1 LAST VOLTAGE 4V
J 0
(-3200 2025);
DISPLAY 0.617021 (-3200 2025);
PAINT SKYBLUE (-3200 2025);
FORCEPROP 1 LAST MATERIAL X6S
J 0
(-3200 1925);
DISPLAY 0.617021 (-3200 1925);
PAINT SKYBLUE (-3200 1925);
FORCEPROP 1 LASTPIN (-3250 1925) $PN 2
J 0
(-3240 1905);
DISPLAY 0.617021 (-3240 1905);
PAINT WHITE (-3240 1905);
FORCEPROP 1 LASTPIN (-3250 2125) $PN 1
J 0
(-3240 2105);
DISPLAY 0.617021 (-3240 2105);
PAINT WHITE (-3240 2105);
FORCEPROP 2 LAST CDS_LIB mstr_discrete
J 0
(-3250 2025);
PAINT MONO (-3250 2025);
DISPLAY INVISIBLE (-3250 2025);
FORCEPROP 2 LAST BOM_COST SB
J 0
(-3200 2225);
DISPLAY 1.361702 (-3200 2225);
PAINT ORANGE (-3200 2225);
DISPLAY INVISIBLE (-3200 2225);
FORCEPROP 2 LAST CDS_SEC 1
J 0
(-3200 2225);
DISPLAY 1.361702 (-3200 2225);
PAINT ORANGE (-3200 2225);
DISPLAY INVISIBLE (-3200 2225);
FORCEPROP 2 LAST $SEC 1
J 0
(-3200 2225);
DISPLAY 0.914894 (-3200 2225);
PAINT MONO (-3200 2225);
DISPLAY INVISIBLE (-3200 2225);
FORCEPROP 2 LAST CDS_LOCATION C8A13
J 0
(-3200 2125);
DISPLAY 0.617021 (-3200 2125);
PAINT AQUA (-3200 2125);
DISPLAY INVISIBLE (-3200 2125);
FORCEPROP 1 LAST PATH I37
J 0
(-3200 2175);
DISPLAY 0.978723 (-3200 2175);
PAINT WHITE (-3200 2175);
DISPLAY INVISIBLE (-3200 2175);
FORCEPROP 2 LAST ROOM SB_DECOUPLING
J 0
(-3200 2175);
DISPLAY 1.361702 (-3200 2175);
PAINT ORANGE (-3200 2175);
DISPLAY INVISIBLE (-3200 2175);
FORCEADD GND..1
(-3025 1650);
FORCEPROP 3 LASTPIN (-3025 1700) SIG_NAME GND\g
J 0
(-3015 1710);
DISPLAY 0.659574 (-3015 1710);
PAINT MONO (-3015 1710);
DISPLAY INVISIBLE (-3015 1710);
FORCEPROP 1 LAST VOLTAGE 0.0V
J 0
(-3070 1607);
DISPLAY 0.340426 (-3070 1607);
PAINT SKYBLUE (-3070 1607);
DISPLAY INVISIBLE (-3070 1607);
FORCEPROP 2 LAST BOM_COST SB
J 0
(-3000 1725);
DISPLAY 1.361702 (-3000 1725);
PAINT ORANGE (-3000 1725);
DISPLAY INVISIBLE (-3000 1725);
FORCEPROP 2 LAST CDS_LIB mstr_symbols
J 0
(-3025 1650);
PAINT MONO (-3025 1650);
DISPLAY INVISIBLE (-3025 1650);
FORCEPROP 1 LAST SIZE 1B
J 0
(-2950 1600);
DISPLAY 1.170213 (-2950 1600);
PAINT AQUA (-2950 1600);
DISPLAY INVISIBLE (-2950 1600);
FORCEPROP 1 LAST BODY_TYPE PLUMBING
J 0
(-3070 1607);
DISPLAY 0.340426 (-3070 1607);
PAINT GREEN (-3070 1607);
DISPLAY INVISIBLE (-3070 1607);
FORCEPROP 1 LAST PATH I38
J 0
(-2950 1650);
DISPLAY 0.872340 (-2950 1650);
PAINT AQUA (-2950 1650);
DISPLAY INVISIBLE (-2950 1650);
FORCEPROP 2 LAST ROOM SB_DECOUPLING
J 0
(-3000 1725);
DISPLAY 1.361702 (-3000 1725);
PAINT ORANGE (-3000 1725);
DISPLAY INVISIBLE (-3000 1725);
FORCEPROP 1 LAST HDL_POWER GND
J 0
(-3025 1800);
DISPLAY 1.170213 (-3025 1800);
PAINT GREEN (-3025 1800);
DISPLAY INVISIBLE (-3025 1800);
FORCEADD CAP_A..1
(-3550 4725);
FORCEPROP 1 LAST LOCATION C2M20
J 0
(-3500 4825);
DISPLAY 0.617021 (-3500 4825);
PAINT AQUA (-3500 4825);
FORCEPROP 1 LAST PART_NUMBER D97712-004
J 0
(-3500 4575);
DISPLAY 0.617021 (-3500 4575);
PAINT BLUE (-3500 4575);
FORCEPROP 1 LAST VALUE 1.0UF
J 0
(-3500 4775);
DISPLAY 0.617021 (-3500 4775);
PAINT SKYBLUE (-3500 4775);
FORCEPROP 1 LAST TOLERANCE 10%
J 0
(-3500 4675);
DISPLAY 0.617021 (-3500 4675);
PAINT SKYBLUE (-3500 4675);
FORCEPROP 1 LAST PACK_TYPE 0402V
J 0
(-3500 4525);
DISPLAY 0.617021 (-3500 4525);
PAINT SKYBLUE (-3500 4525);
FORCEPROP 1 LAST VOLTAGE 6.3V
J 0
(-3500 4725);
DISPLAY 0.617021 (-3500 4725);
PAINT SKYBLUE (-3500 4725);
FORCEPROP 1 LAST MATERIAL X6S
J 0
(-3500 4625);
DISPLAY 0.617021 (-3500 4625);
PAINT SKYBLUE (-3500 4625);
FORCEPROP 1 LASTPIN (-3550 4825) $PN 1
J 0
(-3540 4805);
DISPLAY 0.617021 (-3540 4805);
PAINT WHITE (-3540 4805);
FORCEPROP 1 LASTPIN (-3550 4625) $PN 2
J 0
(-3540 4605);
DISPLAY 0.617021 (-3540 4605);
PAINT WHITE (-3540 4605);
FORCEPROP 2 LAST CDS_LOCATION C2M20
J 0
(-3500 4825);
DISPLAY 0.617021 (-3500 4825);
PAINT AQUA (-3500 4825);
DISPLAY INVISIBLE (-3500 4825);
FORCEPROP 2 LAST BOM_COST SB
J 0
(-3500 4475);
PAINT MONO (-3500 4475);
DISPLAY INVISIBLE (-3500 4475);
FORCEPROP 2 LAST CDS_LIB dev_discrete
J 0
(-3550 4725);
PAINT ORANGE (-3550 4725);
DISPLAY INVISIBLE (-3550 4725);
FORCEPROP 2 LAST CDS_SEC 1
J 0
(-3500 4925);
DISPLAY 1.361702 (-3500 4925);
PAINT ORANGE (-3500 4925);
DISPLAY INVISIBLE (-3500 4925);
FORCEPROP 2 LAST $SEC 1
J 0
(-3500 4925);
DISPLAY 0.914894 (-3500 4925);
PAINT MONO (-3500 4925);
DISPLAY INVISIBLE (-3500 4925);
FORCEPROP 1 LAST PATH I39
J 0
(-3500 4875);
DISPLAY 0.978723 (-3500 4875);
PAINT WHITE (-3500 4875);
DISPLAY INVISIBLE (-3500 4875);
FORCEPROP 2 LAST ROOM SB_DECOUPLING
J 0
(-3550 4725);
PAINT WHITE (-3550 4725);
DISPLAY INVISIBLE (-3550 4725);
FORCEADD CAP_A..1
(-425 4975);
FORCEPROP 1 LAST LOCATION C7B21
J 0
(-375 5075);
DISPLAY 0.617021 (-375 5075);
PAINT AQUA (-375 5075);
FORCEPROP 1 LAST PART_NUMBER E15431-004
J 0
(-375 4825);
DISPLAY 0.617021 (-375 4825);
PAINT BLUE (-375 4825);
FORCEPROP 1 LAST VALUE 22.0UF
J 0
(-375 5025);
DISPLAY 0.617021 (-375 5025);
PAINT SKYBLUE (-375 5025);
FORCEPROP 1 LAST TOLERANCE 20%
J 0
(-375 4925);
DISPLAY 0.617021 (-375 4925);
PAINT SKYBLUE (-375 4925);
FORCEPROP 1 LAST PACK_TYPE 0603V
J 0
(-375 4775);
DISPLAY 0.617021 (-375 4775);
PAINT SKYBLUE (-375 4775);
FORCEPROP 1 LAST VOLTAGE 4V
J 0
(-375 4975);
DISPLAY 0.617021 (-375 4975);
PAINT SKYBLUE (-375 4975);
FORCEPROP 1 LAST MATERIAL X6S
J 0
(-375 4875);
DISPLAY 0.617021 (-375 4875);
PAINT SKYBLUE (-375 4875);
FORCEPROP 2 LAST CDS_LOCATION C7B21
J 0
(-375 5075);
DISPLAY 0.617021 (-375 5075);
PAINT AQUA (-375 5075);
DISPLAY INVISIBLE (-375 5075);
FORCEPROP 2 LAST BOM_COST SB
J 0
(-375 4725);
PAINT MONO (-375 4725);
DISPLAY INVISIBLE (-375 4725);
FORCEPROP 2 LAST CDS_LIB dev_discrete
J 0
(-425 4975);
PAINT ORANGE (-425 4975);
DISPLAY INVISIBLE (-425 4975);
FORCEPROP 2 LAST CDS_SEC 1
J 0
(-375 5175);
DISPLAY 1.361702 (-375 5175);
PAINT ORANGE (-375 5175);
DISPLAY INVISIBLE (-375 5175);
FORCEPROP 2 LAST $SEC 1
J 0
(-375 5175);
DISPLAY 0.914894 (-375 5175);
PAINT MONO (-375 5175);
DISPLAY INVISIBLE (-375 5175);
FORCEPROP 1 LAST PATH I4
J 0
(-375 5125);
DISPLAY 0.978723 (-375 5125);
PAINT WHITE (-375 5125);
DISPLAY INVISIBLE (-375 5125);
FORCEPROP 2 LAST ROOM SB_DECOUPLING
J 0
(-425 4975);
PAINT WHITE (-425 4975);
DISPLAY INVISIBLE (-425 4975);
FORCEPROP 1 LASTPIN (-425 5075) $PN 1
J 0
(-415 5055);
DISPLAY 1.063830 (-415 5055);
PAINT WHITE (-415 5055);
DISPLAY INVISIBLE (-415 5055);
FORCEPROP 1 LASTPIN (-425 4875) $PN 2
J 0
(-415 4855);
DISPLAY 1.063830 (-415 4855);
PAINT WHITE (-415 4855);
DISPLAY INVISIBLE (-415 4855);
FORCEADD CAP_A..1
(-3950 4725);
FORCEPROP 1 LAST LOCATION C2N13
J 0
(-3900 4825);
DISPLAY 0.617021 (-3900 4825);
PAINT AQUA (-3900 4825);
FORCEPROP 1 LAST PART_NUMBER D97712-004
J 0
(-3900 4575);
DISPLAY 0.617021 (-3900 4575);
PAINT BLUE (-3900 4575);
FORCEPROP 1 LAST VALUE 1.0UF
J 0
(-3900 4775);
DISPLAY 0.617021 (-3900 4775);
PAINT SKYBLUE (-3900 4775);
FORCEPROP 1 LAST TOLERANCE 10%
J 0
(-3900 4675);
DISPLAY 0.617021 (-3900 4675);
PAINT SKYBLUE (-3900 4675);
FORCEPROP 1 LAST PACK_TYPE 0402V
J 0
(-3900 4525);
DISPLAY 0.617021 (-3900 4525);
PAINT SKYBLUE (-3900 4525);
FORCEPROP 1 LAST VOLTAGE 6.3V
J 0
(-3900 4725);
DISPLAY 0.617021 (-3900 4725);
PAINT SKYBLUE (-3900 4725);
FORCEPROP 1 LAST MATERIAL X6S
J 0
(-3900 4625);
DISPLAY 0.617021 (-3900 4625);
PAINT SKYBLUE (-3900 4625);
FORCEPROP 1 LASTPIN (-3950 4825) $PN 1
J 0
(-3940 4805);
DISPLAY 0.617021 (-3940 4805);
PAINT WHITE (-3940 4805);
FORCEPROP 1 LASTPIN (-3950 4625) $PN 2
J 0
(-3940 4605);
DISPLAY 0.617021 (-3940 4605);
PAINT WHITE (-3940 4605);
FORCEPROP 2 LAST CDS_LOCATION C2N13
J 0
(-3900 4825);
DISPLAY 0.617021 (-3900 4825);
PAINT AQUA (-3900 4825);
DISPLAY INVISIBLE (-3900 4825);
FORCEPROP 2 LAST BOM_COST SB
J 0
(-3900 4475);
PAINT MONO (-3900 4475);
DISPLAY INVISIBLE (-3900 4475);
FORCEPROP 2 LAST CDS_LIB dev_discrete
J 0
(-3950 4725);
PAINT ORANGE (-3950 4725);
DISPLAY INVISIBLE (-3950 4725);
FORCEPROP 2 LAST CDS_SEC 1
J 0
(-3900 4925);
DISPLAY 1.361702 (-3900 4925);
PAINT ORANGE (-3900 4925);
DISPLAY INVISIBLE (-3900 4925);
FORCEPROP 2 LAST $SEC 1
J 0
(-3900 4925);
DISPLAY 0.914894 (-3900 4925);
PAINT MONO (-3900 4925);
DISPLAY INVISIBLE (-3900 4925);
FORCEPROP 1 LAST PATH I40
J 0
(-3900 4875);
DISPLAY 0.978723 (-3900 4875);
PAINT WHITE (-3900 4875);
DISPLAY INVISIBLE (-3900 4875);
FORCEPROP 2 LAST ROOM SB_DECOUPLING
J 0
(-3950 4725);
PAINT WHITE (-3950 4725);
DISPLAY INVISIBLE (-3950 4725);
FORCEADD CAP_A..1
(-4350 4725);
FORCEPROP 1 LAST LOCATION C2N2
J 0
(-4300 4825);
DISPLAY 0.617021 (-4300 4825);
PAINT AQUA (-4300 4825);
FORCEPROP 1 LAST PART_NUMBER D97712-004
J 0
(-4300 4575);
DISPLAY 0.617021 (-4300 4575);
PAINT BLUE (-4300 4575);
FORCEPROP 1 LAST VALUE 1.0UF
J 0
(-4300 4775);
DISPLAY 0.617021 (-4300 4775);
PAINT SKYBLUE (-4300 4775);
FORCEPROP 1 LAST TOLERANCE 10%
J 0
(-4300 4675);
DISPLAY 0.617021 (-4300 4675);
PAINT SKYBLUE (-4300 4675);
FORCEPROP 1 LAST PACK_TYPE 0402V
J 0
(-4300 4525);
DISPLAY 0.617021 (-4300 4525);
PAINT SKYBLUE (-4300 4525);
FORCEPROP 1 LAST VOLTAGE 6.3V
J 0
(-4300 4725);
DISPLAY 0.617021 (-4300 4725);
PAINT SKYBLUE (-4300 4725);
FORCEPROP 1 LAST MATERIAL X6S
J 0
(-4300 4625);
DISPLAY 0.617021 (-4300 4625);
PAINT SKYBLUE (-4300 4625);
FORCEPROP 1 LASTPIN (-4350 4825) $PN 1
J 0
(-4340 4805);
DISPLAY 0.617021 (-4340 4805);
PAINT WHITE (-4340 4805);
FORCEPROP 1 LASTPIN (-4350 4625) $PN 2
J 0
(-4340 4605);
DISPLAY 0.617021 (-4340 4605);
PAINT WHITE (-4340 4605);
FORCEPROP 2 LAST CDS_LOCATION C2N2
J 0
(-4300 4825);
DISPLAY 0.617021 (-4300 4825);
PAINT AQUA (-4300 4825);
DISPLAY INVISIBLE (-4300 4825);
FORCEPROP 2 LAST BOM_COST SB
J 0
(-4300 4475);
PAINT MONO (-4300 4475);
DISPLAY INVISIBLE (-4300 4475);
FORCEPROP 2 LAST CDS_LIB dev_discrete
J 0
(-4350 4725);
PAINT ORANGE (-4350 4725);
DISPLAY INVISIBLE (-4350 4725);
FORCEPROP 2 LAST CDS_SEC 1
J 0
(-4300 4925);
DISPLAY 1.361702 (-4300 4925);
PAINT ORANGE (-4300 4925);
DISPLAY INVISIBLE (-4300 4925);
FORCEPROP 2 LAST $SEC 1
J 0
(-4300 4925);
DISPLAY 0.914894 (-4300 4925);
PAINT MONO (-4300 4925);
DISPLAY INVISIBLE (-4300 4925);
FORCEPROP 1 LAST PATH I41
J 0
(-4300 4875);
DISPLAY 0.978723 (-4300 4875);
PAINT WHITE (-4300 4875);
DISPLAY INVISIBLE (-4300 4875);
FORCEPROP 2 LAST ROOM SB_DECOUPLING
J 0
(-4350 4725);
PAINT WHITE (-4350 4725);
DISPLAY INVISIBLE (-4350 4725);
FORCEADD CAP_A..1
(-3600 3525);
FORCEPROP 1 LAST LOCATION C3M43
J 0
(-3550 3625);
DISPLAY 0.617021 (-3550 3625);
PAINT AQUA (-3550 3625);
FORCEPROP 1 LAST PART_NUMBER D97712-004
J 0
(-3550 3375);
DISPLAY 0.617021 (-3550 3375);
PAINT BLUE (-3550 3375);
FORCEPROP 1 LAST VALUE 1.0UF
J 0
(-3550 3575);
DISPLAY 0.617021 (-3550 3575);
PAINT SKYBLUE (-3550 3575);
FORCEPROP 1 LAST TOLERANCE 10%
J 0
(-3550 3475);
DISPLAY 0.617021 (-3550 3475);
PAINT SKYBLUE (-3550 3475);
FORCEPROP 1 LAST PACK_TYPE 0402V
J 0
(-3550 3325);
DISPLAY 0.617021 (-3550 3325);
PAINT SKYBLUE (-3550 3325);
FORCEPROP 1 LAST VOLTAGE 6.3V
J 0
(-3550 3525);
DISPLAY 0.617021 (-3550 3525);
PAINT SKYBLUE (-3550 3525);
FORCEPROP 1 LAST MATERIAL X6S
J 0
(-3550 3425);
DISPLAY 0.617021 (-3550 3425);
PAINT SKYBLUE (-3550 3425);
FORCEPROP 1 LASTPIN (-3600 3625) $PN 1
J 0
(-3590 3605);
DISPLAY 0.617021 (-3590 3605);
PAINT WHITE (-3590 3605);
FORCEPROP 1 LASTPIN (-3600 3425) $PN 2
J 0
(-3590 3405);
DISPLAY 0.617021 (-3590 3405);
PAINT WHITE (-3590 3405);
FORCEPROP 2 LAST CDS_LOCATION C3M43
J 0
(-3550 3625);
DISPLAY 0.617021 (-3550 3625);
PAINT AQUA (-3550 3625);
DISPLAY INVISIBLE (-3550 3625);
FORCEPROP 2 LAST BOM_COST SB
J 0
(-3550 3275);
PAINT MONO (-3550 3275);
DISPLAY INVISIBLE (-3550 3275);
FORCEPROP 2 LAST CDS_LIB dev_discrete
J 0
(-3600 3525);
PAINT ORANGE (-3600 3525);
DISPLAY INVISIBLE (-3600 3525);
FORCEPROP 2 LAST CDS_SEC 1
J 0
(-3550 3725);
DISPLAY 1.361702 (-3550 3725);
PAINT ORANGE (-3550 3725);
DISPLAY INVISIBLE (-3550 3725);
FORCEPROP 2 LAST $SEC 1
J 0
(-3550 3725);
DISPLAY 0.914894 (-3550 3725);
PAINT MONO (-3550 3725);
DISPLAY INVISIBLE (-3550 3725);
FORCEPROP 1 LAST PATH I42
J 0
(-3550 3675);
DISPLAY 0.978723 (-3550 3675);
PAINT WHITE (-3550 3675);
DISPLAY INVISIBLE (-3550 3675);
FORCEPROP 2 LAST ROOM SB_DECOUPLING
J 0
(-3600 3525);
PAINT WHITE (-3600 3525);
DISPLAY INVISIBLE (-3600 3525);
FORCEADD CAP_A..1
(-4000 3525);
FORCEPROP 1 LAST LOCATION C2N7
J 0
(-3950 3625);
DISPLAY 0.617021 (-3950 3625);
PAINT AQUA (-3950 3625);
FORCEPROP 1 LAST PART_NUMBER D97712-004
J 0
(-3950 3375);
DISPLAY 0.617021 (-3950 3375);
PAINT BLUE (-3950 3375);
FORCEPROP 1 LAST VALUE 1.0UF
J 0
(-3950 3575);
DISPLAY 0.617021 (-3950 3575);
PAINT SKYBLUE (-3950 3575);
FORCEPROP 1 LAST TOLERANCE 10%
J 0
(-3950 3475);
DISPLAY 0.617021 (-3950 3475);
PAINT SKYBLUE (-3950 3475);
FORCEPROP 1 LAST PACK_TYPE 0402V
J 0
(-3950 3325);
DISPLAY 0.617021 (-3950 3325);
PAINT SKYBLUE (-3950 3325);
FORCEPROP 1 LAST VOLTAGE 6.3V
J 0
(-3950 3525);
DISPLAY 0.617021 (-3950 3525);
PAINT SKYBLUE (-3950 3525);
FORCEPROP 1 LAST MATERIAL X6S
J 0
(-3950 3425);
DISPLAY 0.617021 (-3950 3425);
PAINT SKYBLUE (-3950 3425);
FORCEPROP 1 LASTPIN (-4000 3625) $PN 1
J 0
(-3990 3605);
DISPLAY 0.617021 (-3990 3605);
PAINT WHITE (-3990 3605);
FORCEPROP 1 LASTPIN (-4000 3425) $PN 2
J 0
(-3990 3405);
DISPLAY 0.617021 (-3990 3405);
PAINT WHITE (-3990 3405);
FORCEPROP 2 LAST CDS_LOCATION C2N7
J 0
(-3950 3625);
DISPLAY 0.617021 (-3950 3625);
PAINT AQUA (-3950 3625);
DISPLAY INVISIBLE (-3950 3625);
FORCEPROP 2 LAST BOM_COST SB
J 0
(-3950 3275);
PAINT MONO (-3950 3275);
DISPLAY INVISIBLE (-3950 3275);
FORCEPROP 2 LAST CDS_LIB dev_discrete
J 0
(-4000 3525);
PAINT ORANGE (-4000 3525);
DISPLAY INVISIBLE (-4000 3525);
FORCEPROP 2 LAST CDS_SEC 1
J 0
(-3950 3725);
DISPLAY 1.361702 (-3950 3725);
PAINT ORANGE (-3950 3725);
DISPLAY INVISIBLE (-3950 3725);
FORCEPROP 2 LAST $SEC 1
J 0
(-3950 3725);
DISPLAY 0.914894 (-3950 3725);
PAINT MONO (-3950 3725);
DISPLAY INVISIBLE (-3950 3725);
FORCEPROP 1 LAST PATH I43
J 0
(-3950 3675);
DISPLAY 0.978723 (-3950 3675);
PAINT WHITE (-3950 3675);
DISPLAY INVISIBLE (-3950 3675);
FORCEPROP 2 LAST ROOM SB_DECOUPLING
J 0
(-4000 3525);
PAINT WHITE (-4000 3525);
DISPLAY INVISIBLE (-4000 3525);
FORCEADD CAP_A..1
(-4375 3525);
FORCEPROP 1 LAST LOCATION C3M39
J 0
(-4325 3625);
DISPLAY 0.617021 (-4325 3625);
PAINT AQUA (-4325 3625);
FORCEPROP 1 LAST PART_NUMBER D97712-004
J 0
(-4325 3375);
DISPLAY 0.617021 (-4325 3375);
PAINT BLUE (-4325 3375);
FORCEPROP 1 LAST VALUE 1.0UF
J 0
(-4325 3575);
DISPLAY 0.617021 (-4325 3575);
PAINT SKYBLUE (-4325 3575);
FORCEPROP 1 LAST TOLERANCE 10%
J 0
(-4325 3475);
DISPLAY 0.617021 (-4325 3475);
PAINT SKYBLUE (-4325 3475);
FORCEPROP 1 LAST PACK_TYPE 0402V
J 0
(-4325 3325);
DISPLAY 0.617021 (-4325 3325);
PAINT SKYBLUE (-4325 3325);
FORCEPROP 1 LAST VOLTAGE 6.3V
J 0
(-4325 3525);
DISPLAY 0.617021 (-4325 3525);
PAINT SKYBLUE (-4325 3525);
FORCEPROP 1 LAST MATERIAL X6S
J 0
(-4325 3425);
DISPLAY 0.617021 (-4325 3425);
PAINT SKYBLUE (-4325 3425);
FORCEPROP 1 LASTPIN (-4375 3625) $PN 1
J 0
(-4365 3605);
DISPLAY 0.617021 (-4365 3605);
PAINT WHITE (-4365 3605);
FORCEPROP 1 LASTPIN (-4375 3425) $PN 2
J 0
(-4365 3405);
DISPLAY 0.617021 (-4365 3405);
PAINT WHITE (-4365 3405);
FORCEPROP 2 LAST CDS_LOCATION C3M39
J 0
(-4325 3625);
DISPLAY 0.617021 (-4325 3625);
PAINT AQUA (-4325 3625);
DISPLAY INVISIBLE (-4325 3625);
FORCEPROP 2 LAST BOM_COST SB
J 0
(-4325 3275);
PAINT MONO (-4325 3275);
DISPLAY INVISIBLE (-4325 3275);
FORCEPROP 2 LAST CDS_LIB dev_discrete
J 0
(-4375 3525);
PAINT ORANGE (-4375 3525);
DISPLAY INVISIBLE (-4375 3525);
FORCEPROP 2 LAST CDS_SEC 1
J 0
(-4325 3725);
DISPLAY 1.361702 (-4325 3725);
PAINT ORANGE (-4325 3725);
DISPLAY INVISIBLE (-4325 3725);
FORCEPROP 2 LAST $SEC 1
J 0
(-4325 3725);
DISPLAY 0.914894 (-4325 3725);
PAINT MONO (-4325 3725);
DISPLAY INVISIBLE (-4325 3725);
FORCEPROP 1 LAST PATH I44
J 0
(-4325 3675);
DISPLAY 0.978723 (-4325 3675);
PAINT WHITE (-4325 3675);
DISPLAY INVISIBLE (-4325 3675);
FORCEPROP 2 LAST ROOM SB_DECOUPLING
J 0
(-4375 3525);
PAINT WHITE (-4375 3525);
DISPLAY INVISIBLE (-4375 3525);
FORCEADD CAP_A..1
(-4750 4725);
FORCEPROP 1 LAST LOCATION C3M42
J 0
(-4700 4825);
DISPLAY 0.617021 (-4700 4825);
PAINT AQUA (-4700 4825);
FORCEPROP 1 LAST PART_NUMBER D97712-004
J 0
(-4700 4575);
DISPLAY 0.617021 (-4700 4575);
PAINT BLUE (-4700 4575);
FORCEPROP 1 LAST VALUE 1.0UF
J 0
(-4700 4775);
DISPLAY 0.617021 (-4700 4775);
PAINT SKYBLUE (-4700 4775);
FORCEPROP 1 LAST TOLERANCE 10%
J 0
(-4700 4675);
DISPLAY 0.617021 (-4700 4675);
PAINT SKYBLUE (-4700 4675);
FORCEPROP 1 LAST PACK_TYPE 0402V
J 0
(-4700 4525);
DISPLAY 0.617021 (-4700 4525);
PAINT SKYBLUE (-4700 4525);
FORCEPROP 1 LAST VOLTAGE 6.3V
J 0
(-4700 4725);
DISPLAY 0.617021 (-4700 4725);
PAINT SKYBLUE (-4700 4725);
FORCEPROP 1 LAST MATERIAL X6S
J 0
(-4700 4625);
DISPLAY 0.617021 (-4700 4625);
PAINT SKYBLUE (-4700 4625);
FORCEPROP 1 LASTPIN (-4750 4825) $PN 1
J 0
(-4740 4805);
DISPLAY 0.617021 (-4740 4805);
PAINT WHITE (-4740 4805);
FORCEPROP 1 LASTPIN (-4750 4625) $PN 2
J 0
(-4740 4605);
DISPLAY 0.617021 (-4740 4605);
PAINT WHITE (-4740 4605);
FORCEPROP 2 LAST CDS_LOCATION C3M42
J 0
(-4700 4825);
DISPLAY 0.617021 (-4700 4825);
PAINT AQUA (-4700 4825);
DISPLAY INVISIBLE (-4700 4825);
FORCEPROP 2 LAST BOM_COST SB
J 0
(-4700 4475);
PAINT MONO (-4700 4475);
DISPLAY INVISIBLE (-4700 4475);
FORCEPROP 2 LAST CDS_LIB dev_discrete
J 0
(-4750 4725);
PAINT ORANGE (-4750 4725);
DISPLAY INVISIBLE (-4750 4725);
FORCEPROP 2 LAST CDS_SEC 1
J 0
(-4700 4925);
DISPLAY 1.361702 (-4700 4925);
PAINT ORANGE (-4700 4925);
DISPLAY INVISIBLE (-4700 4925);
FORCEPROP 2 LAST $SEC 1
J 0
(-4700 4925);
DISPLAY 0.914894 (-4700 4925);
PAINT MONO (-4700 4925);
DISPLAY INVISIBLE (-4700 4925);
FORCEPROP 1 LAST PATH I45
J 0
(-4700 4875);
DISPLAY 0.978723 (-4700 4875);
PAINT WHITE (-4700 4875);
DISPLAY INVISIBLE (-4700 4875);
FORCEPROP 2 LAST ROOM SB_DECOUPLING
J 0
(-4750 4725);
PAINT WHITE (-4750 4725);
DISPLAY INVISIBLE (-4750 4725);
FORCEADD P1V05_PCH_STBY..1
(-4600 3775);
FORCEPROP 3 LASTPIN (-4600 3725) SIG_NAME P1V05_PCH_STBY\g
J 0
(-4590 3735);
DISPLAY 0.659574 (-4590 3735);
PAINT MONO (-4590 3735);
DISPLAY INVISIBLE (-4590 3735);
FORCEPROP 1 LAST VOLTAGE 1.05V
J 0
(-4645 3732);
DISPLAY 0.340426 (-4645 3732);
PAINT SKYBLUE (-4645 3732);
DISPLAY INVISIBLE (-4645 3732);
FORCEPROP 2 LAST BOM_COST SB
J 0
(-4600 3925);
PAINT MONO (-4600 3925);
DISPLAY INVISIBLE (-4600 3925);
FORCEPROP 2 LAST CDS_LIB mstr_symbols
J 0
(-4600 3775);
PAINT ORANGE (-4600 3775);
DISPLAY INVISIBLE (-4600 3775);
FORCEPROP 1 LAST BODY_TYPE PLUMBING
J 0
(-4645 3732);
DISPLAY 0.340426 (-4645 3732);
PAINT GREEN (-4645 3732);
DISPLAY INVISIBLE (-4645 3732);
FORCEPROP 1 LAST PATH I46
J 0
(-4550 3800);
DISPLAY 0.872340 (-4550 3800);
PAINT AQUA (-4550 3800);
DISPLAY INVISIBLE (-4550 3800);
FORCEPROP 2 LAST ROOM SB_DECOUPLING
J 0
(-4600 3875);
DISPLAY 1.361702 (-4600 3875);
PAINT WHITE (-4600 3875);
DISPLAY INVISIBLE (-4600 3875);
FORCEPROP 1 LAST HDL_POWER P1V05_PCH_STBY
J 0
(-4600 3825);
DISPLAY 0.872340 (-4600 3825);
PAINT GREEN (-4600 3825);
DISPLAY INVISIBLE (-4600 3825);
FORCEADD CAP_A..1
(-4775 3525);
FORCEPROP 1 LAST LOCATION C2N8
J 0
(-4725 3625);
DISPLAY 0.617021 (-4725 3625);
PAINT AQUA (-4725 3625);
FORCEPROP 1 LAST PART_NUMBER D97712-004
J 0
(-4725 3375);
DISPLAY 0.617021 (-4725 3375);
PAINT BLUE (-4725 3375);
FORCEPROP 1 LAST VALUE 1.0UF
J 0
(-4725 3575);
DISPLAY 0.617021 (-4725 3575);
PAINT SKYBLUE (-4725 3575);
FORCEPROP 1 LAST TOLERANCE 10%
J 0
(-4725 3475);
DISPLAY 0.617021 (-4725 3475);
PAINT SKYBLUE (-4725 3475);
FORCEPROP 1 LAST PACK_TYPE 0402V
J 0
(-4725 3325);
DISPLAY 0.617021 (-4725 3325);
PAINT SKYBLUE (-4725 3325);
FORCEPROP 1 LAST VOLTAGE 6.3V
J 0
(-4725 3525);
DISPLAY 0.617021 (-4725 3525);
PAINT SKYBLUE (-4725 3525);
FORCEPROP 1 LAST MATERIAL X6S
J 0
(-4725 3425);
DISPLAY 0.617021 (-4725 3425);
PAINT SKYBLUE (-4725 3425);
FORCEPROP 1 LASTPIN (-4775 3625) $PN 1
J 0
(-4765 3605);
DISPLAY 0.617021 (-4765 3605);
PAINT WHITE (-4765 3605);
FORCEPROP 1 LASTPIN (-4775 3425) $PN 2
J 0
(-4765 3405);
DISPLAY 0.617021 (-4765 3405);
PAINT WHITE (-4765 3405);
FORCEPROP 2 LAST CDS_LOCATION C2N8
J 0
(-4725 3625);
DISPLAY 0.617021 (-4725 3625);
PAINT AQUA (-4725 3625);
DISPLAY INVISIBLE (-4725 3625);
FORCEPROP 2 LAST BOM_COST SB
J 0
(-4725 3275);
PAINT MONO (-4725 3275);
DISPLAY INVISIBLE (-4725 3275);
FORCEPROP 2 LAST CDS_LIB dev_discrete
J 0
(-4775 3525);
PAINT ORANGE (-4775 3525);
DISPLAY INVISIBLE (-4775 3525);
FORCEPROP 2 LAST CDS_SEC 1
J 0
(-4725 3725);
DISPLAY 1.361702 (-4725 3725);
PAINT ORANGE (-4725 3725);
DISPLAY INVISIBLE (-4725 3725);
FORCEPROP 2 LAST $SEC 1
J 0
(-4725 3725);
DISPLAY 0.914894 (-4725 3725);
PAINT MONO (-4725 3725);
DISPLAY INVISIBLE (-4725 3725);
FORCEPROP 1 LAST PATH I47
J 0
(-4725 3675);
DISPLAY 0.978723 (-4725 3675);
PAINT WHITE (-4725 3675);
DISPLAY INVISIBLE (-4725 3675);
FORCEPROP 2 LAST ROOM SB_DECOUPLING
J 0
(-4775 3525);
PAINT WHITE (-4775 3525);
DISPLAY INVISIBLE (-4775 3525);
FORCEADD CAP_A..1
(-4250 2100);
FORCEPROP 1 LAST LOCATION C2M13
J 0
(-4200 2200);
DISPLAY 0.617021 (-4200 2200);
PAINT AQUA (-4200 2200);
FORCEPROP 1 LAST PART_NUMBER E15431-004
J 0
(-4200 1950);
DISPLAY 0.617021 (-4200 1950);
PAINT BLUE (-4200 1950);
FORCEPROP 1 LAST VALUE 22.0UF
J 0
(-4200 2150);
DISPLAY 0.617021 (-4200 2150);
PAINT SKYBLUE (-4200 2150);
FORCEPROP 1 LAST TOLERANCE 20%
J 0
(-4200 2050);
DISPLAY 0.617021 (-4200 2050);
PAINT SKYBLUE (-4200 2050);
FORCEPROP 1 LAST PACK_TYPE 0603V
J 0
(-4200 1900);
DISPLAY 0.617021 (-4200 1900);
PAINT SKYBLUE (-4200 1900);
FORCEPROP 1 LAST VOLTAGE 4V
J 0
(-4200 2100);
DISPLAY 0.617021 (-4200 2100);
PAINT SKYBLUE (-4200 2100);
FORCEPROP 1 LAST MATERIAL X6S
J 0
(-4200 2000);
DISPLAY 0.617021 (-4200 2000);
PAINT SKYBLUE (-4200 2000);
FORCEPROP 1 LASTPIN (-4250 2200) $PN 1
J 0
(-4240 2180);
DISPLAY 0.617021 (-4240 2180);
PAINT ORANGE (-4240 2180);
FORCEPROP 1 LASTPIN (-4250 2000) $PN 2
J 0
(-4240 1980);
DISPLAY 0.617021 (-4240 1980);
PAINT ORANGE (-4240 1980);
FORCEPROP 2 LAST CDS_LOCATION C2M13
J 0
(-4200 2200);
DISPLAY 0.617021 (-4200 2200);
PAINT AQUA (-4200 2200);
DISPLAY INVISIBLE (-4200 2200);
FORCEPROP 2 LAST BOM_COST SB
J 0
(-4200 2300);
DISPLAY 1.361702 (-4200 2300);
PAINT ORANGE (-4200 2300);
DISPLAY INVISIBLE (-4200 2300);
FORCEPROP 2 LAST CDS_LIB dev_discrete
J 0
(-4250 2100);
PAINT ORANGE (-4250 2100);
DISPLAY INVISIBLE (-4250 2100);
FORCEPROP 2 LAST CDS_SEC 1
J 0
(-4200 2300);
DISPLAY 1.361702 (-4200 2300);
PAINT ORANGE (-4200 2300);
DISPLAY INVISIBLE (-4200 2300);
FORCEPROP 2 LAST $SEC 1
J 0
(-4200 2300);
DISPLAY 0.914894 (-4200 2300);
PAINT MONO (-4200 2300);
DISPLAY INVISIBLE (-4200 2300);
FORCEPROP 1 LAST PATH I48
J 0
(-4200 2250);
DISPLAY 0.978723 (-4200 2250);
PAINT WHITE (-4200 2250);
DISPLAY INVISIBLE (-4200 2250);
FORCEPROP 2 LAST ROOM SB_DECOUPLING
J 0
(-4200 2250);
DISPLAY 1.361702 (-4200 2250);
PAINT ORANGE (-4200 2250);
DISPLAY INVISIBLE (-4200 2250);
FORCEADD P1V05_PCH_STBY..1
(-4800 2400);
FORCEPROP 3 LASTPIN (-4800 2350) SIG_NAME P1V05_PCH_STBY\g
J 0
(-4790 2360);
DISPLAY 0.659574 (-4790 2360);
PAINT MONO (-4790 2360);
DISPLAY INVISIBLE (-4790 2360);
FORCEPROP 1 LAST VOLTAGE 1.05V
J 0
(-4845 2357);
DISPLAY 0.340426 (-4845 2357);
PAINT SKYBLUE (-4845 2357);
DISPLAY INVISIBLE (-4845 2357);
FORCEPROP 2 LAST BOM_COST SB
J 0
(-4800 2500);
DISPLAY 1.361702 (-4800 2500);
PAINT ORANGE (-4800 2500);
DISPLAY INVISIBLE (-4800 2500);
FORCEPROP 2 LAST CDS_LIB mstr_symbols
J 0
(-4800 2400);
PAINT ORANGE (-4800 2400);
DISPLAY INVISIBLE (-4800 2400);
FORCEPROP 1 LAST BODY_TYPE PLUMBING
J 0
(-4845 2357);
DISPLAY 0.340426 (-4845 2357);
PAINT GREEN (-4845 2357);
DISPLAY INVISIBLE (-4845 2357);
FORCEPROP 1 LAST PATH I49
J 0
(-4750 2425);
DISPLAY 0.872340 (-4750 2425);
PAINT AQUA (-4750 2425);
DISPLAY INVISIBLE (-4750 2425);
FORCEPROP 2 LAST ROOM SB_DECOUPLING
J 0
(-4800 2500);
DISPLAY 1.361702 (-4800 2500);
PAINT ORANGE (-4800 2500);
DISPLAY INVISIBLE (-4800 2500);
FORCEPROP 1 LAST HDL_POWER P1V05_PCH_STBY
J 0
(-4800 2450);
DISPLAY 0.872340 (-4800 2450);
PAINT GREEN (-4800 2450);
DISPLAY INVISIBLE (-4800 2450);
FORCEADD P1V05_PCH_STBY..1
(-600 5225);
FORCEPROP 3 LASTPIN (-600 5175) SIG_NAME P1V05_PCH_STBY\g
J 0
(-590 5185);
DISPLAY 0.659574 (-590 5185);
PAINT MONO (-590 5185);
DISPLAY INVISIBLE (-590 5185);
FORCEPROP 1 LAST VOLTAGE 1.05V
J 0
(-645 5182);
DISPLAY 0.340426 (-645 5182);
PAINT SKYBLUE (-645 5182);
DISPLAY INVISIBLE (-645 5182);
FORCEPROP 2 LAST BOM_COST SB
J 0
(-600 5375);
PAINT MONO (-600 5375);
DISPLAY INVISIBLE (-600 5375);
FORCEPROP 2 LAST CDS_LIB mstr_symbols
J 0
(-600 5225);
PAINT ORANGE (-600 5225);
DISPLAY INVISIBLE (-600 5225);
FORCEPROP 1 LAST BODY_TYPE PLUMBING
J 0
(-645 5182);
DISPLAY 0.340426 (-645 5182);
PAINT GREEN (-645 5182);
DISPLAY INVISIBLE (-645 5182);
FORCEPROP 1 LAST PATH I5
J 0
(-550 5250);
DISPLAY 0.872340 (-550 5250);
PAINT AQUA (-550 5250);
DISPLAY INVISIBLE (-550 5250);
FORCEPROP 2 LAST ROOM SB_DECOUPLING
J 0
(-600 5325);
DISPLAY 1.361702 (-600 5325);
PAINT WHITE (-600 5325);
DISPLAY INVISIBLE (-600 5325);
FORCEPROP 1 LAST HDL_POWER P1V05_PCH_STBY
J 0
(-600 5275);
DISPLAY 0.872340 (-600 5275);
PAINT GREEN (-600 5275);
DISPLAY INVISIBLE (-600 5275);
FORCEADD CAP_A..1
(-4650 2100);
FORCEPROP 1 LAST LOCATION C2N10
J 0
(-4600 2200);
DISPLAY 0.617021 (-4600 2200);
PAINT AQUA (-4600 2200);
FORCEPROP 1 LAST PART_NUMBER E15431-004
J 0
(-4600 1950);
DISPLAY 0.617021 (-4600 1950);
PAINT BLUE (-4600 1950);
FORCEPROP 1 LAST VALUE 22.0UF
J 0
(-4600 2150);
DISPLAY 0.617021 (-4600 2150);
PAINT SKYBLUE (-4600 2150);
FORCEPROP 1 LAST TOLERANCE 20%
J 0
(-4600 2050);
DISPLAY 0.617021 (-4600 2050);
PAINT SKYBLUE (-4600 2050);
FORCEPROP 1 LAST PACK_TYPE 0603V
J 0
(-4600 1900);
DISPLAY 0.617021 (-4600 1900);
PAINT SKYBLUE (-4600 1900);
FORCEPROP 1 LAST VOLTAGE 4V
J 0
(-4600 2100);
DISPLAY 0.617021 (-4600 2100);
PAINT SKYBLUE (-4600 2100);
FORCEPROP 1 LAST MATERIAL X6S
J 0
(-4600 2000);
DISPLAY 0.617021 (-4600 2000);
PAINT SKYBLUE (-4600 2000);
FORCEPROP 1 LASTPIN (-4650 2200) $PN 1
J 0
(-4640 2180);
DISPLAY 0.617021 (-4640 2180);
PAINT WHITE (-4640 2180);
FORCEPROP 1 LASTPIN (-4650 2000) $PN 2
J 0
(-4640 1980);
DISPLAY 0.617021 (-4640 1980);
PAINT WHITE (-4640 1980);
FORCEPROP 2 LAST CDS_LOCATION C2N10
J 0
(-4600 2200);
DISPLAY 0.617021 (-4600 2200);
PAINT AQUA (-4600 2200);
DISPLAY INVISIBLE (-4600 2200);
FORCEPROP 2 LAST BOM_COST SB
J 0
(-4600 2300);
DISPLAY 1.361702 (-4600 2300);
PAINT ORANGE (-4600 2300);
DISPLAY INVISIBLE (-4600 2300);
FORCEPROP 2 LAST CDS_LIB dev_discrete
J 0
(-4650 2100);
PAINT ORANGE (-4650 2100);
DISPLAY INVISIBLE (-4650 2100);
FORCEPROP 2 LAST CDS_SEC 1
J 0
(-4600 2300);
DISPLAY 1.361702 (-4600 2300);
PAINT ORANGE (-4600 2300);
DISPLAY INVISIBLE (-4600 2300);
FORCEPROP 2 LAST $SEC 1
J 0
(-4600 2300);
DISPLAY 0.914894 (-4600 2300);
PAINT MONO (-4600 2300);
DISPLAY INVISIBLE (-4600 2300);
FORCEPROP 1 LAST PATH I50
J 0
(-4600 2250);
DISPLAY 0.978723 (-4600 2250);
PAINT WHITE (-4600 2250);
DISPLAY INVISIBLE (-4600 2250);
FORCEPROP 2 LAST ROOM SB_DECOUPLING
J 0
(-4600 2250);
DISPLAY 1.361702 (-4600 2250);
PAINT ORANGE (-4600 2250);
DISPLAY INVISIBLE (-4600 2250);
FORCEADD GND..1
(-4800 1725);
FORCEPROP 3 LASTPIN (-4800 1775) SIG_NAME GND\g
J 0
(-4790 1785);
DISPLAY 0.659574 (-4790 1785);
PAINT MONO (-4790 1785);
DISPLAY INVISIBLE (-4790 1785);
FORCEPROP 1 LAST VOLTAGE 0.0V
J 0
(-4845 1682);
DISPLAY 0.340426 (-4845 1682);
PAINT SKYBLUE (-4845 1682);
DISPLAY INVISIBLE (-4845 1682);
FORCEPROP 2 LAST CDS_LIB mstr_symbols
J 0
(-4800 1725);
PAINT MONO (-4800 1725);
DISPLAY INVISIBLE (-4800 1725);
FORCEPROP 1 LAST SIZE 1B
J 0
(-4725 1675);
DISPLAY 1.170213 (-4725 1675);
PAINT AQUA (-4725 1675);
DISPLAY INVISIBLE (-4725 1675);
FORCEPROP 2 LAST BOM_COST SB
J 0
(-4775 1800);
DISPLAY 1.361702 (-4775 1800);
PAINT ORANGE (-4775 1800);
DISPLAY INVISIBLE (-4775 1800);
FORCEPROP 1 LAST BODY_TYPE PLUMBING
J 0
(-4845 1682);
DISPLAY 0.340426 (-4845 1682);
PAINT GREEN (-4845 1682);
DISPLAY INVISIBLE (-4845 1682);
FORCEPROP 1 LAST PATH I51
J 0
(-4725 1725);
DISPLAY 0.872340 (-4725 1725);
PAINT AQUA (-4725 1725);
DISPLAY INVISIBLE (-4725 1725);
FORCEPROP 2 LAST ROOM SB_DECOUPLING
J 0
(-4775 1800);
DISPLAY 1.361702 (-4775 1800);
PAINT ORANGE (-4775 1800);
DISPLAY INVISIBLE (-4775 1800);
FORCEPROP 1 LAST HDL_POWER GND
J 0
(-4800 1875);
DISPLAY 1.170213 (-4800 1875);
PAINT GREEN (-4800 1875);
DISPLAY INVISIBLE (-4800 1875);
FORCEADD CAP_A..1
(-5075 2100);
FORCEPROP 1 LAST LOCATION C2M12
J 0
(-5025 2200);
DISPLAY 0.617021 (-5025 2200);
PAINT AQUA (-5025 2200);
FORCEPROP 1 LAST PART_NUMBER E15431-004
J 0
(-5025 1950);
DISPLAY 0.617021 (-5025 1950);
PAINT BLUE (-5025 1950);
FORCEPROP 1 LAST VALUE 22.0UF
J 0
(-5025 2150);
DISPLAY 0.617021 (-5025 2150);
PAINT SKYBLUE (-5025 2150);
FORCEPROP 1 LAST TOLERANCE 20%
J 0
(-5025 2050);
DISPLAY 0.617021 (-5025 2050);
PAINT SKYBLUE (-5025 2050);
FORCEPROP 1 LAST PACK_TYPE 0603V
J 0
(-5025 1900);
DISPLAY 0.617021 (-5025 1900);
PAINT SKYBLUE (-5025 1900);
FORCEPROP 1 LAST VOLTAGE 4V
J 0
(-5025 2100);
DISPLAY 0.617021 (-5025 2100);
PAINT SKYBLUE (-5025 2100);
FORCEPROP 1 LAST MATERIAL X6S
J 0
(-5025 2000);
DISPLAY 0.617021 (-5025 2000);
PAINT SKYBLUE (-5025 2000);
FORCEPROP 1 LASTPIN (-5075 2200) $PN 1
J 0
(-5065 2180);
DISPLAY 0.617021 (-5065 2180);
PAINT WHITE (-5065 2180);
FORCEPROP 1 LASTPIN (-5075 2000) $PN 2
J 0
(-5065 1980);
DISPLAY 0.617021 (-5065 1980);
PAINT WHITE (-5065 1980);
FORCEPROP 2 LAST CDS_LOCATION C2M12
J 0
(-5025 2200);
DISPLAY 0.617021 (-5025 2200);
PAINT AQUA (-5025 2200);
DISPLAY INVISIBLE (-5025 2200);
FORCEPROP 2 LAST BOM_COST SB
J 0
(-5025 2300);
DISPLAY 1.361702 (-5025 2300);
PAINT ORANGE (-5025 2300);
DISPLAY INVISIBLE (-5025 2300);
FORCEPROP 2 LAST CDS_LIB dev_discrete
J 0
(-5075 2100);
PAINT ORANGE (-5075 2100);
DISPLAY INVISIBLE (-5075 2100);
FORCEPROP 2 LAST CDS_SEC 1
J 0
(-5025 2300);
DISPLAY 1.361702 (-5025 2300);
PAINT ORANGE (-5025 2300);
DISPLAY INVISIBLE (-5025 2300);
FORCEPROP 2 LAST $SEC 1
J 0
(-5025 2300);
DISPLAY 0.914894 (-5025 2300);
PAINT MONO (-5025 2300);
DISPLAY INVISIBLE (-5025 2300);
FORCEPROP 1 LAST PATH I52
J 0
(-5025 2250);
DISPLAY 0.978723 (-5025 2250);
PAINT WHITE (-5025 2250);
DISPLAY INVISIBLE (-5025 2250);
FORCEPROP 2 LAST ROOM SB_DECOUPLING
J 0
(-5025 2250);
DISPLAY 1.361702 (-5025 2250);
PAINT ORANGE (-5025 2250);
DISPLAY INVISIBLE (-5025 2250);
FORCEADD CAP_A..1
(-875 4975);
FORCEPROP 1 LAST LOCATION C7B20
J 0
(-825 5075);
DISPLAY 0.617021 (-825 5075);
PAINT AQUA (-825 5075);
FORCEPROP 1 LAST PART_NUMBER E15431-004
J 0
(-825 4825);
DISPLAY 0.617021 (-825 4825);
PAINT BLUE (-825 4825);
FORCEPROP 1 LAST VALUE 22.0UF
J 0
(-825 5025);
DISPLAY 0.617021 (-825 5025);
PAINT SKYBLUE (-825 5025);
FORCEPROP 1 LAST TOLERANCE 20%
J 0
(-825 4925);
DISPLAY 0.617021 (-825 4925);
PAINT SKYBLUE (-825 4925);
FORCEPROP 1 LAST PACK_TYPE 0603V
J 0
(-825 4775);
DISPLAY 0.617021 (-825 4775);
PAINT SKYBLUE (-825 4775);
FORCEPROP 1 LAST VOLTAGE 4V
J 0
(-825 4975);
DISPLAY 0.617021 (-825 4975);
PAINT SKYBLUE (-825 4975);
FORCEPROP 1 LAST MATERIAL X6S
J 0
(-825 4875);
DISPLAY 0.617021 (-825 4875);
PAINT SKYBLUE (-825 4875);
FORCEPROP 2 LAST CDS_LOCATION C7B20
J 0
(-825 5075);
DISPLAY 0.617021 (-825 5075);
PAINT AQUA (-825 5075);
DISPLAY INVISIBLE (-825 5075);
FORCEPROP 2 LAST BOM_COST SB
J 0
(-825 4725);
PAINT MONO (-825 4725);
DISPLAY INVISIBLE (-825 4725);
FORCEPROP 2 LAST CDS_LIB dev_discrete
J 0
(-875 4975);
PAINT ORANGE (-875 4975);
DISPLAY INVISIBLE (-875 4975);
FORCEPROP 2 LAST CDS_SEC 1
J 0
(-825 5175);
DISPLAY 1.361702 (-825 5175);
PAINT ORANGE (-825 5175);
DISPLAY INVISIBLE (-825 5175);
FORCEPROP 2 LAST $SEC 1
J 0
(-825 5175);
DISPLAY 0.914894 (-825 5175);
PAINT MONO (-825 5175);
DISPLAY INVISIBLE (-825 5175);
FORCEPROP 1 LAST PATH I6
J 0
(-825 5125);
DISPLAY 0.978723 (-825 5125);
PAINT WHITE (-825 5125);
DISPLAY INVISIBLE (-825 5125);
FORCEPROP 2 LAST ROOM SB_DECOUPLING
J 0
(-875 4975);
PAINT WHITE (-875 4975);
DISPLAY INVISIBLE (-875 4975);
FORCEPROP 1 LASTPIN (-875 5075) $PN 1
J 0
(-865 5055);
DISPLAY 1.063830 (-865 5055);
PAINT WHITE (-865 5055);
DISPLAY INVISIBLE (-865 5055);
FORCEPROP 1 LASTPIN (-875 4875) $PN 2
J 0
(-865 4855);
DISPLAY 1.063830 (-865 4855);
PAINT WHITE (-865 4855);
DISPLAY INVISIBLE (-865 4855);
FORCEADD CAP_A..1
(975 4025);
FORCEPROP 1 LAST LOCATION C7B23
J 0
(1025 4125);
DISPLAY 0.617021 (1025 4125);
PAINT AQUA (1025 4125);
FORCEPROP 1 LAST PART_NUMBER E15431-004
J 0
(1025 3875);
DISPLAY 0.617021 (1025 3875);
PAINT BLUE (1025 3875);
FORCEPROP 1 LAST VALUE 22.0UF
J 0
(1025 4075);
DISPLAY 0.617021 (1025 4075);
PAINT SKYBLUE (1025 4075);
FORCEPROP 1 LAST TOLERANCE 20%
J 0
(1025 3975);
DISPLAY 0.617021 (1025 3975);
PAINT SKYBLUE (1025 3975);
FORCEPROP 1 LAST PACK_TYPE 0603V
J 0
(1025 3825);
DISPLAY 0.617021 (1025 3825);
PAINT SKYBLUE (1025 3825);
FORCEPROP 1 LAST VOLTAGE 4V
J 0
(1025 4025);
DISPLAY 0.617021 (1025 4025);
PAINT SKYBLUE (1025 4025);
FORCEPROP 1 LAST MATERIAL X6S
J 0
(1025 3925);
DISPLAY 0.617021 (1025 3925);
PAINT SKYBLUE (1025 3925);
FORCEPROP 2 LAST CDS_LOCATION C7B23
J 0
(1025 4125);
DISPLAY 0.617021 (1025 4125);
PAINT AQUA (1025 4125);
DISPLAY INVISIBLE (1025 4125);
FORCEPROP 2 LAST BOM_COST SB
J 0
(1025 3775);
PAINT MONO (1025 3775);
DISPLAY INVISIBLE (1025 3775);
FORCEPROP 2 LAST CDS_LIB dev_discrete
J 0
(975 4025);
PAINT ORANGE (975 4025);
DISPLAY INVISIBLE (975 4025);
FORCEPROP 2 LAST CDS_SEC 1
J 0
(1025 4225);
DISPLAY 1.361702 (1025 4225);
PAINT ORANGE (1025 4225);
DISPLAY INVISIBLE (1025 4225);
FORCEPROP 2 LAST $SEC 1
J 0
(1025 4225);
DISPLAY 0.914894 (1025 4225);
PAINT MONO (1025 4225);
DISPLAY INVISIBLE (1025 4225);
FORCEPROP 1 LAST PATH I7
J 0
(1025 4175);
DISPLAY 0.978723 (1025 4175);
PAINT WHITE (1025 4175);
DISPLAY INVISIBLE (1025 4175);
FORCEPROP 2 LAST ROOM SB_DECOUPLING
J 0
(975 4025);
PAINT WHITE (975 4025);
DISPLAY INVISIBLE (975 4025);
FORCEPROP 1 LASTPIN (975 4125) $PN 1
J 0
(985 4105);
DISPLAY 1.063830 (985 4105);
PAINT WHITE (985 4105);
DISPLAY INVISIBLE (985 4105);
FORCEPROP 1 LASTPIN (975 3925) $PN 2
J 0
(985 3905);
DISPLAY 1.063830 (985 3905);
PAINT WHITE (985 3905);
DISPLAY INVISIBLE (985 3905);
FORCEADD CAP_A..1
(950 3025);
FORCEPROP 1 LAST LOCATION C8B10
J 0
(1000 3125);
DISPLAY 0.617021 (1000 3125);
PAINT AQUA (1000 3125);
FORCEPROP 1 LAST PART_NUMBER E15431-004
J 0
(1000 2875);
DISPLAY 0.617021 (1000 2875);
PAINT BLUE (1000 2875);
FORCEPROP 1 LAST VALUE 22.0UF
J 0
(1000 3075);
DISPLAY 0.617021 (1000 3075);
PAINT SKYBLUE (1000 3075);
FORCEPROP 1 LAST TOLERANCE 20%
J 0
(1000 2975);
DISPLAY 0.617021 (1000 2975);
PAINT SKYBLUE (1000 2975);
FORCEPROP 1 LAST PACK_TYPE 0603V
J 0
(1000 2825);
DISPLAY 0.617021 (1000 2825);
PAINT SKYBLUE (1000 2825);
FORCEPROP 1 LAST VOLTAGE 4V
J 0
(1000 3025);
DISPLAY 0.617021 (1000 3025);
PAINT SKYBLUE (1000 3025);
FORCEPROP 1 LAST MATERIAL X6S
J 0
(1000 2925);
DISPLAY 0.617021 (1000 2925);
PAINT SKYBLUE (1000 2925);
FORCEPROP 1 LASTPIN (950 3125) $PN 1
J 0
(960 3105);
DISPLAY 0.617021 (960 3105);
PAINT WHITE (960 3105);
FORCEPROP 1 LASTPIN (950 2925) $PN 2
J 0
(960 2905);
DISPLAY 0.617021 (960 2905);
PAINT WHITE (960 2905);
FORCEPROP 2 LAST CDS_LOCATION C8B10
J 0
(1000 3125);
DISPLAY 0.617021 (1000 3125);
PAINT AQUA (1000 3125);
DISPLAY INVISIBLE (1000 3125);
FORCEPROP 2 LAST BOM_COST SB
J 0
(1000 3225);
DISPLAY 1.361702 (1000 3225);
PAINT ORANGE (1000 3225);
DISPLAY INVISIBLE (1000 3225);
FORCEPROP 2 LAST CDS_LIB dev_discrete
J 0
(950 3025);
PAINT ORANGE (950 3025);
DISPLAY INVISIBLE (950 3025);
FORCEPROP 2 LAST CDS_SEC 1
J 0
(1000 3225);
DISPLAY 1.361702 (1000 3225);
PAINT ORANGE (1000 3225);
DISPLAY INVISIBLE (1000 3225);
FORCEPROP 2 LAST $SEC 1
J 0
(1000 3225);
DISPLAY 0.914894 (1000 3225);
PAINT MONO (1000 3225);
DISPLAY INVISIBLE (1000 3225);
FORCEPROP 1 LAST PATH I8
J 0
(1000 3175);
DISPLAY 0.978723 (1000 3175);
PAINT WHITE (1000 3175);
DISPLAY INVISIBLE (1000 3175);
FORCEPROP 2 LAST ROOM SB_DECOUPLING
J 0
(1000 3175);
DISPLAY 1.361702 (1000 3175);
PAINT ORANGE (1000 3175);
DISPLAY INVISIBLE (1000 3175);
FORCEADD GND..1
(275 4625);
FORCEPROP 3 LASTPIN (275 4675) SIG_NAME GND\g
J 0
(285 4685);
DISPLAY 0.659574 (285 4685);
PAINT MONO (285 4685);
DISPLAY INVISIBLE (285 4685);
FORCEPROP 1 LAST VOLTAGE 0
J 0
(275 4625);
PAINT SKYBLUE (275 4625);
DISPLAY INVISIBLE (275 4625);
FORCEPROP 1 LAST SIZE 1B
J 0
(350 4575);
DISPLAY 1.404255 (350 4575);
PAINT GREEN (350 4575);
DISPLAY INVISIBLE (350 4575);
FORCEPROP 2 LAST CDS_LIB mstr_symbols
J 0
(275 4625);
PAINT ORANGE (275 4625);
DISPLAY INVISIBLE (275 4625);
FORCEPROP 2 LAST BOM_COST SB
J 0
(225 4700);
PAINT MONO (225 4700);
DISPLAY INVISIBLE (225 4700);
FORCEPROP 1 LAST BODY_TYPE PLUMBING
J 0
(230 4582);
DISPLAY 0.340426 (230 4582);
PAINT GREEN (230 4582);
DISPLAY INVISIBLE (230 4582);
FORCEPROP 1 LAST PATH I9
J 0
(350 4625);
DISPLAY 0.872340 (350 4625);
PAINT AQUA (350 4625);
DISPLAY INVISIBLE (350 4625);
FORCEPROP 2 LAST ROOM SB_DECOUPLING
J 0
(-200 4700);
PAINT WHITE (-200 4700);
DISPLAY INVISIBLE (-200 4700);
FORCEPROP 1 LAST HDL_POWER GND
J 0
(275 4775);
DISPLAY 1.404255 (275 4775);
PAINT GREEN (275 4775);
DISPLAY INVISIBLE (275 4775);
FORCEADD CAD_NOTE..1
(-900 1425);
FORCEPROP 0 LAST L2 EDGE OF THE PKG.
J 0
(-1050 1225);
DISPLAY 1.063830 (-1050 1225);
PAINT WHITE (-1050 1225);
FORCEPROP 0 LAST L1 PLACE CAPS ON THE
J 0
(-1050 1300);
DISPLAY 1.063830 (-1050 1300);
PAINT WHITE (-1050 1300);
FORCEPROP 2 LAST CDS_LIB mstr_symbols
J 0
(-900 1425);
PAINT ORANGE (-900 1425);
DISPLAY INVISIBLE (-900 1425);
FORCEPROP 2 LAST BOM_COST SB
J 0
(-1050 1375);
PAINT MONO (-1050 1375);
DISPLAY INVISIBLE (-1050 1375);
FORCEPROP 1 LAST COMMENT_BODY TRUE
J 0
(-875 1525);
DISPLAY 1.319149 (-875 1525);
PAINT GREEN (-875 1525);
DISPLAY INVISIBLE (-875 1525);
FORCEPROP 2 LAST ROOM SB_DECOUPLING
J 0
(-1050 1375);
PAINT WHITE (-1050 1375);
DISPLAY INVISIBLE (-1050 1375);
FORCEADD DESIGN_NOTE..1
(1350 1400);
FORCEPROP 0 LAST L1 P1V05_PCH_STBY DECOUPLING CAPS
J 0
(1150 1275);
DISPLAY 1.063830 (1150 1275);
PAINT WHITE (1150 1275);
FORCEPROP 2 LAST BOM_COST SB
J 0
(1150 1325);
DISPLAY 1.361702 (1150 1325);
PAINT ORANGE (1150 1325);
DISPLAY INVISIBLE (1150 1325);
FORCEPROP 2 LAST CDS_LIB mstr_symbols
J 0
(1350 1400);
PAINT ORANGE (1350 1400);
DISPLAY INVISIBLE (1350 1400);
FORCEPROP 1 LAST COMMENT_BODY TRUE
J 0
(1375 1500);
DISPLAY 1.319149 (1375 1500);
PAINT ORANGE (1375 1500);
DISPLAY INVISIBLE (1375 1500);
FORCEPROP 2 LAST ROOM SB_DECOUPLING
J 0
(1150 1325);
DISPLAY 1.361702 (1150 1325);
PAINT WHITE (1150 1325);
DISPLAY INVISIBLE (1150 1325);
FORCEADD INTEL_CORP_BPAGE..1
(2650 500);
FORCEPROP 1 LAST CDS_CON_LAST_MODIFIED Tue Dec 01 11:52:00 2015
J 0
(1225 825);
PAINT ORANGE (1225 825);
DISPLAY INVISIBLE (1225 825);
FORCEPROP 1 LAST CUSTOM_TXT_CDS <CURRENT_DESIGN_SHEET> OF <TOTAL_DESIGN_SHEETS>
J 0
(2150 525);
PAINT GREEN (2150 525);
FORCEPROP 1 LAST CUSTOM_TXT_CDS <CON_LAST_MODIFIED>
J 0
(725 850);
PAINT GREEN (725 850);
FORCEPROP 2 LAST CUSTOM_TXT_CDS <XR_PAGE_TITLE>
J 0
(-5240 5750);
DISPLAY 0.638298 (-5240 5750);
PAINT PINK (-5240 5750);
DISPLAY INVISIBLE (-5240 5750);
FORCEPROP 1 LAST SCH_ADDRESS3 Santa Clara, CA 95052-8119
J 0
(-1325 525);
DISPLAY 0.617021 (-1325 525);
PAINT GREEN (-1325 525);
FORCEPROP 1 LAST SCH_ADDRESS2 P.O. BOX 58119
J 0
(-1325 575);
DISPLAY 0.617021 (-1325 575);
PAINT GREEN (-1325 575);
FORCEPROP 1 LAST SCH_ADDRESS1 2200 Mission College Blvd.
J 0
(-1325 625);
DISPLAY 0.617021 (-1325 625);
PAINT GREEN (-1325 625);
FORCEPROP 1 LAST SCH_TITLE PCH DECOUPLING 2/3
J 0
(-5300 550);
DISPLAY 1.212766 (-5300 550);
PAINT ORANGE (-5300 550);
FORCEPROP 1 LAST SCH_NUMBER H4694802
J 0
(1350 650);
DISPLAY 1.212766 (1350 650);
PAINT YELLOW (1350 650);
FORCEPROP 1 LAST SCH_DEPT BESD
J 1
(-1800 600);
DISPLAY 1.212766 (-1800 600);
PAINT YELLOW (-1800 600);
FORCEPROP 1 LAST SCH_REV 2.420
J 0
(2400 650);
DISPLAY 0.978723 (2400 650);
PAINT YELLOW (2400 650);
FORCEPROP 2 LAST CDS_LIB mstr_symbols
J 0
(2650 500);
PAINT MONO (2650 500);
DISPLAY INVISIBLE (2650 500);
FORCEPROP 2 LAST PAGE_BORDER TRUE
J 0
(-5240 5750);
DISPLAY 0.851064 (-5240 5750);
PAINT PINK (-5240 5750);
DISPLAY INVISIBLE (-5240 5750);
FORCEPROP 1 LAST COMMENT_BODY TRUE
J 0
(2662 512);
DISPLAY 0.468085 (2662 512);
PAINT GREEN (2662 512);
DISPLAY INVISIBLE (2662 512);
FORCEPROP 2 LAST ROOM WBG_DECOUPLING
J 0
(-5225 5800);
PAINT MONO (-5225 5800);
DISPLAY INVISIBLE (-5225 5800);
FORCEPROP 2 LAST CDS_XR_PAGE_TITLE CR-131 : @BASEBOARD_FAB2_LIB.BASEBOARD_FAB2(SCH_1):PAGE131
J 0
(-5240 5750);
DISPLAY 0.638298 (-5240 5750);
PAINT PINK (-5240 5750);
DISPLAY INVISIBLE (-5240 5750);
FORCEADD CAD_NOTE..1
(-3200 1425);
FORCEPROP 0 LAST L2 
J 0
(-3350 1275);
DISPLAY 1.063830 (-3350 1275);
PAINT WHITE (-3350 1275);
FORCEPROP 0 LAST L1 PLACE CAPS ON THE SECONDARY SIDE OF BGA
J 0
(-3350 1300);
DISPLAY 1.063830 (-3350 1300);
PAINT WHITE (-3350 1300);
FORCEPROP 2 LAST CDS_LIB mstr_symbols
J 0
(-3200 1425);
PAINT ORANGE (-3200 1425);
DISPLAY INVISIBLE (-3200 1425);
FORCEPROP 2 LAST BOM_COST SB
J 0
(-3350 1375);
PAINT MONO (-3350 1375);
DISPLAY INVISIBLE (-3350 1375);
FORCEPROP 1 LAST COMMENT_BODY TRUE
J 0
(-3175 1525);
DISPLAY 1.319149 (-3175 1525);
PAINT GREEN (-3175 1525);
DISPLAY INVISIBLE (-3175 1525);
FORCEPROP 2 LAST ROOM SB_DECOUPLING
J 0
(-3350 1375);
PAINT WHITE (-3350 1375);
DISPLAY INVISIBLE (-3350 1375);
FORCEADD CAD_NOTE..1
(-4925 1450);
FORCEPROP 0 LAST L2 STYLE NEAR TO PIN.
J 0
(-5075 1250);
DISPLAY 1.063830 (-5075 1250);
PAINT WHITE (-5075 1250);
FORCEPROP 0 LAST L1 PLACE CAPS BSC
J 0
(-5075 1325);
DISPLAY 1.063830 (-5075 1325);
PAINT WHITE (-5075 1325);
FORCEPROP 2 LAST BOM_COST SB
J 0
(-5075 1400);
PAINT MONO (-5075 1400);
DISPLAY INVISIBLE (-5075 1400);
FORCEPROP 2 LAST CDS_LIB mstr_symbols
J 0
(-4925 1450);
PAINT ORANGE (-4925 1450);
DISPLAY INVISIBLE (-4925 1450);
FORCEPROP 1 LAST COMMENT_BODY TRUE
J 0
(-4900 1550);
DISPLAY 1.319149 (-4900 1550);
PAINT GREEN (-4900 1550);
DISPLAY INVISIBLE (-4900 1550);
FORCEPROP 2 LAST ROOM SB_DECOUPLING
J 0
(-5075 1400);
PAINT WHITE (-5075 1400);
DISPLAY INVISIBLE (-5075 1400);
WIRE 16 -1 (-875 3925)(-875 3750);
WIRE 16 -1 (-875 3750)(-425 3750);
WIRE 16 -1 (-425 3925)(-425 3750);
WIRE 16 -1 (50 3750)(-425 3750);
WIRE 16 -1 (50 3925)(50 3750);
WIRE 16 -1 (50 3750)(275 3750);
WIRE 16 -1 (275 3750)(500 3750);
WIRE 16 -1 (275 3750)(275 3700);
WIRE 16 -1 (975 3750)(500 3750);
WIRE 16 -1 (500 3925)(500 3750);
WIRE 16 -1 (975 3925)(975 3750);
WIRE 16 -1 (975 4125)(975 4200);
WIRE 16 -1 (975 4200)(500 4200);
WIRE 16 -1 (500 4125)(500 4200);
WIRE 16 -1 (500 4200)(50 4200);
WIRE 16 -1 (50 4125)(50 4200);
WIRE 16 -1 (-425 4200)(50 4200);
WIRE 16 -1 (-425 4125)(-425 4200);
WIRE 16 -1 (-625 4200)(-425 4200);
WIRE 16 -1 (-625 4200)(-875 4200);
WIRE 16 -1 (-625 4200)(-625 4250);
WIRE 16 -1 (-875 4125)(-875 4200);
WIRE 16 -1 (950 3225)(950 3125);
WIRE 16 -1 (950 3225)(500 3225);
WIRE 16 -1 (500 3125)(500 3225);
WIRE 16 -1 (500 3225)(50 3225);
WIRE 16 -1 (50 3125)(50 3225);
WIRE 16 -1 (50 3225)(-400 3225);
WIRE 16 -1 (-400 3125)(-400 3225);
WIRE 16 -1 (-400 3225)(-625 3225);
WIRE 16 -1 (-850 3225)(-625 3225);
WIRE 16 -1 (-625 3275)(-625 3225);
WIRE 16 -1 (-850 3125)(-850 3225);
WIRE 16 -1 (-850 2925)(-850 2775);
WIRE 16 -1 (-400 2775)(-850 2775);
WIRE 16 -1 (-400 2925)(-400 2775);
WIRE 16 -1 (50 2775)(-400 2775);
WIRE 16 -1 (50 2925)(50 2775);
WIRE 16 -1 (50 2775)(275 2775);
WIRE 16 -1 (500 2775)(275 2775);
WIRE 16 -1 (275 2775)(275 2725);
WIRE 16 -1 (950 2775)(500 2775);
WIRE 16 -1 (500 2925)(500 2775);
WIRE 16 -1 (950 2925)(950 2775);
WIRE 16 -1 (50 2125)(50 2225);
WIRE 16 -1 (50 2225)(-175 2225);
WIRE 16 -1 (-175 2225)(-400 2225);
WIRE 16 -1 (-175 2275)(-175 2225);
WIRE 16 -1 (-400 2125)(-400 2225);
WIRE 16 -1 (50 1925)(50 1775);
WIRE 16 -1 (50 1775)(-175 1775);
WIRE 16 -1 (-175 1775)(-400 1775);
WIRE 16 -1 (-175 1775)(-175 1700);
WIRE 16 -1 (-400 1925)(-400 1775);
WIRE 16 -1 (-2375 4900)(-2375 4825);
WIRE 16 -1 (-2800 4900)(-2375 4900);
WIRE 16 -1 (-2800 4900)(-2800 4825);
WIRE 16 -1 (-3175 4900)(-2800 4900);
WIRE 16 -1 (-3175 4825)(-3175 4900);
WIRE 16 -1 (-3175 4900)(-3550 4900);
WIRE 16 -1 (-3550 4825)(-3550 4900);
WIRE 16 -1 (-3550 4900)(-3950 4900);
WIRE 16 -1 (-3950 4825)(-3950 4900);
WIRE 16 -1 (-3950 4900)(-4350 4900);
WIRE 16 -1 (-4350 4825)(-4350 4900);
WIRE 16 -1 (-4575 4900)(-4350 4900);
WIRE 16 -1 (-4750 4900)(-4575 4900);
WIRE 16 -1 (-4575 4900)(-4575 4950);
WIRE 16 -1 (-4750 4825)(-4750 4900);
WIRE 16 -1 (-4750 4625)(-4750 4475);
WIRE 16 -1 (-4750 4475)(-4350 4475);
WIRE 16 -1 (-4350 4625)(-4350 4475);
WIRE 16 -1 (-3950 4475)(-4350 4475);
WIRE 16 -1 (-3950 4625)(-3950 4475);
WIRE 16 -1 (-3550 4475)(-3950 4475);
WIRE 16 -1 (-3550 4625)(-3550 4475);
WIRE 16 -1 (-3350 4475)(-3550 4475);
WIRE 16 -1 (-3350 4475)(-3175 4475);
WIRE 16 -1 (-3350 4475)(-3350 4425);
WIRE 16 -1 (-2800 4475)(-3175 4475);
WIRE 16 -1 (-3175 4625)(-3175 4475);
WIRE 16 -1 (-2375 4475)(-2800 4475);
WIRE 16 -1 (-2800 4625)(-2800 4475);
WIRE 16 -1 (-2375 4625)(-2375 4475);
WIRE 16 -1 (-4775 3425)(-4775 3275);
WIRE 16 -1 (-4775 3275)(-4375 3275);
WIRE 16 -1 (-4375 3425)(-4375 3275);
WIRE 16 -1 (-4000 3275)(-4375 3275);
WIRE 16 -1 (-4000 3425)(-4000 3275);
WIRE 16 -1 (-3600 3275)(-4000 3275);
WIRE 16 -1 (-3600 3425)(-3600 3275);
WIRE 16 -1 (-3425 3275)(-3600 3275);
WIRE 16 -1 (-3425 3275)(-3225 3275);
WIRE 16 -1 (-3425 3275)(-3425 3225);
WIRE 16 -1 (-2850 3275)(-3225 3275);
WIRE 16 -1 (-3225 3425)(-3225 3275);
WIRE 16 -1 (-2850 3425)(-2850 3275);
WIRE 16 -1 (-2400 2125)(-2400 2225);
WIRE 16 -1 (-2800 2225)(-2400 2225);
WIRE 16 -1 (-2800 2125)(-2800 2225);
WIRE 16 -1 (-2800 2225)(-3025 2225);
WIRE 16 -1 (-3025 2225)(-3250 2225);
WIRE 16 -1 (-3025 2275)(-3025 2225);
WIRE 16 -1 (-3250 2125)(-3250 2225);
WIRE 16 -1 (-2400 1775)(-2400 1925);
WIRE 16 -1 (-2800 1775)(-2400 1775);
WIRE 16 -1 (-2800 1925)(-2800 1775);
WIRE 16 -1 (-2800 1775)(-3025 1775);
WIRE 16 -1 (-3025 1775)(-3250 1775);
WIRE 16 -1 (-3025 1775)(-3025 1700);
WIRE 16 -1 (-3250 1925)(-3250 1775);
WIRE 16 -1 (-2850 3625)(-2850 3700);
WIRE 16 -1 (-3225 3700)(-2850 3700);
WIRE 16 -1 (-3225 3625)(-3225 3700);
WIRE 16 -1 (-3225 3700)(-3600 3700);
WIRE 16 -1 (-3600 3625)(-3600 3700);
WIRE 16 -1 (-3600 3700)(-4000 3700);
WIRE 16 -1 (-4000 3625)(-4000 3700);
WIRE 16 -1 (-4000 3700)(-4375 3700);
WIRE 16 -1 (-4375 3625)(-4375 3700);
WIRE 16 -1 (-4600 3700)(-4375 3700);
WIRE 16 -1 (-4775 3700)(-4600 3700);
WIRE 16 -1 (-4600 3700)(-4600 3725);
WIRE 16 -1 (-4775 3625)(-4775 3700);
WIRE 16 -1 (-4250 2275)(-4250 2200);
WIRE 16 -1 (-4650 2275)(-4250 2275);
WIRE 16 -1 (-4650 2200)(-4650 2275);
WIRE 16 -1 (-4650 2275)(-4800 2275);
WIRE 16 -1 (-5075 2275)(-4800 2275);
WIRE 16 -1 (-4800 2350)(-4800 2275);
WIRE 16 -1 (-5075 2200)(-5075 2275);
WIRE 16 -1 (975 5075)(975 5150);
WIRE 16 -1 (975 5150)(500 5150);
WIRE 16 -1 (500 5075)(500 5150);
WIRE 16 -1 (500 5150)(50 5150);
WIRE 16 -1 (50 5075)(50 5150);
WIRE 16 -1 (-425 5150)(50 5150);
WIRE 16 -1 (-425 5075)(-425 5150);
WIRE 16 -1 (-600 5150)(-425 5150);
WIRE 16 -1 (-600 5150)(-875 5150);
WIRE 16 -1 (-600 5150)(-600 5175);
WIRE 16 -1 (-875 5075)(-875 5150);
WIRE 16 -1 (-4250 2000)(-4250 1850);
WIRE 16 -1 (-4250 1850)(-4650 1850);
WIRE 16 -1 (-4650 2000)(-4650 1850);
WIRE 16 -1 (-4800 1850)(-4650 1850);
WIRE 16 -1 (-4800 1850)(-5075 1850);
WIRE 16 -1 (-4800 1850)(-4800 1775);
WIRE 16 -1 (-5075 2000)(-5075 1850);
WIRE 16 -1 (-875 4875)(-875 4725);
WIRE 16 -1 (-875 4725)(-425 4725);
WIRE 16 -1 (-425 4875)(-425 4725);
WIRE 16 -1 (50 4725)(-425 4725);
WIRE 16 -1 (50 4875)(50 4725);
WIRE 16 -1 (50 4725)(275 4725);
WIRE 16 -1 (275 4725)(500 4725);
WIRE 16 -1 (275 4725)(275 4675);
WIRE 16 -1 (975 4725)(500 4725);
WIRE 16 -1 (500 4875)(500 4725);
WIRE 16 -1 (975 4875)(975 4725);
WIRE 16 273 (-1550 5400)(-1550 900);
DOT 1 (-4575 4900);
DOT 1 (-3175 4900);
DOT 1 (500 2775);
DOT 1 (500 4725);
DOT 1 (-4800 1850);
DOT 1 (-4650 1850);
DOT 1 (-4800 2275);
DOT 1 (-4650 2275);
DOT 1 (-4600 3700);
DOT 1 (-4375 3275);
DOT 1 (-4000 3275);
DOT 1 (-3600 3275);
DOT 1 (-3600 3700);
DOT 1 (-4000 3700);
DOT 1 (-4375 3700);
DOT 1 (-4350 4475);
DOT 1 (-3950 4475);
DOT 1 (-3550 4475);
DOT 1 (-3025 2225);
DOT 1 (-3025 1775);
DOT 1 (-2800 1775);
DOT 1 (-2800 2225);
DOT 1 (-3425 3275);
DOT 1 (-3225 3275);
DOT 1 (-3225 3700);
DOT 1 (-3175 4475);
DOT 1 (-4350 4900);
DOT 1 (-3550 4900);
DOT 1 (-2800 4900);
DOT 1 (-175 1775);
DOT 1 (-175 2225);
DOT 1 (-625 3225);
DOT 1 (-625 4200);
DOT 1 (-400 2775);
DOT 1 (-400 3225);
DOT 1 (50 3225);
DOT 1 (50 2775);
DOT 1 (275 2775);
DOT 1 (500 3225);
DOT 1 (-425 3750);
DOT 1 (-425 4200);
DOT 1 (50 4200);
DOT 1 (50 3750);
DOT 1 (275 3750);
DOT 1 (500 3750);
DOT 1 (500 4200);
DOT 1 (275 4725);
DOT 1 (50 4725);
DOT 1 (-425 4725);
DOT 1 (-425 5150);
DOT 1 (50 5150);
DOT 1 (500 5150);
DOT 1 (-600 5150);
DOT 1 (-3950 4900);
DOT 1 (-2800 4475);
DOT 1 (-3350 4475);
FORCENOTE
ROOM=LBG_DECOUPLING
(-5288 917) 0;
DISPLAY LEFT (-5288 917);
DISPLAY 1.361702 (-5288 917);
PAINT PURPLE (-5288 917);
FORCENOTE
BOM_COST=SB
(-5288 817) 0;
DISPLAY LEFT (-5288 817);
DISPLAY 1.361702 (-5288 817);
PAINT PURPLE (-5288 817);
QUIT
